(lib_symbols
	(symbol "TPS566231P_1"
			(exclude_from_sim no)
			(in_bom yes)
			(on_board yes)
			(property "Reference" "U"
				(at 33.02 -2.54 0)
				(effects
					(font
						(size 1.27 1.27)
						(thickness 0.15)
					)
					(justify left bottom)
				)
			)
			(property "Value" "TPS566231P"
				(at 33.02 -5.08 0)
				(effects
					(font
						(size 1.27 1.27)
						(thickness 0.15)
					)
					(justify left bottom)
					(hide yes)
				)
			)
			(property "Footprint" "antmicro-footprints:VQFN-HR-9_2x1.5mm"
				(at 33.02 -7.62 0)
				(effects
					(font
						(size 1.27 1.27)
						(thickness 0.15)
					)
					(justify left bottom)
					(hide yes)
				)
			)
			(property "Datasheet" "https://www.ti.com/lit/ds/symlink/tps566231.pdf"
				(at 33.02 -10.16 0)
				(effects
					(font
						(size 1.27 1.27)
						(thickness 0.15)
					)
					(justify left bottom)
					(hide yes)
				)
			)
			(property "Description" "Switching Voltage Regulators 3-V to 18-V, 6-A synchronous buck converter"
				(at 33.02 -22.86 0)
				(effects
					(font
						(size 1.27 1.27)
					)
					(justify left bottom)
					(hide yes)
				)
			)
			(property "Manufacturer" "Texas Instruments"
				(at 33.02 -12.7 0)
				(effects
					(font
						(size 1.27 1.27)
						(thickness 0.15)
					)
					(justify left bottom)
					(hide yes)
				)
			)
			(property "MPN" "TPS566231PRQFR"
				(at 33.02 -15.24 0)
				(effects
					(font
						(size 1.27 1.27)
						(thickness 0.15)
					)
					(justify left bottom)
				)
			)
			(property "Author" "Antmicro"
				(at 33.02 -17.78 0)
				(effects
					(font
						(size 1.27 1.27)
						(thickness 0.15)
					)
					(justify left bottom)
					(hide yes)
				)
			)
			(property "License" "Apache-2.0"
				(at 33.02 -20.32 0)
				(effects
					(font
						(size 1.27 1.27)
						(thickness 0.15)
					)
					(justify left bottom)
					(hide yes)
				)
			)
			(property "ki_keywords" "SMT, PMIC, IC, SWITCHING, VOLTAGE, REGULATOR, DC-DC"
				(at 0 0 0)
				(effects
					(font
						(size 1.27 1.27)
					)
					(hide yes)
				)
			)
			(symbol "TPS566231P_1_1_1"
				(rectangle
					(start 2.54 2.54)
					(end 15.24 -17.78)
					(stroke
						(width 0.254)
						(type default)
					)
					(fill
						(type background)
					)
				)
				(pin power_in line
					(at 0 0 0)
					(length 2.54)
					(name "V_{IN}"
						(effects
							(font
								(size 1.27 1.27)
							)
						)
					)
					(number "5"
						(effects
							(font
								(size 1.27 1.27)
							)
						)
					)
				)
				(pin passive line
					(at 0 0 0)
					(length 2.54)
					(hide yes)
					(name "V_{IN}"
						(effects
							(font
								(size 1.27 1.27)
							)
						)
					)
					(number "6"
						(effects
							(font
								(size 1.27 1.27)
							)
						)
					)
				)
				(pin passive line
					(at 0 -2.54 0)
					(length 2.54)
					(name "V_{CC}"
						(effects
							(font
								(size 1.27 1.27)
							)
						)
					)
					(number "1"
						(effects
							(font
								(size 1.27 1.27)
							)
						)
					)
				)
				(pin input line
					(at 0 -10.16 0)
					(length 2.54)
					(name "EN"
						(effects
							(font
								(size 1.27 1.27)
							)
						)
					)
					(number "3"
						(effects
							(font
								(size 1.27 1.27)
							)
						)
					)
				)
				(pin passive line
					(at 0 -15.24 0)
					(length 2.54)
					(name "PG"
						(effects
							(font
								(size 1.27 1.27)
							)
						)
					)
					(number "9"
						(effects
							(font
								(size 1.27 1.27)
							)
						)
					)
				)
				(pin power_out line
					(at 17.78 0 180)
					(length 2.54)
					(name "SW"
						(effects
							(font
								(size 1.27 1.27)
							)
						)
					)
					(number "8"
						(effects
							(font
								(size 1.27 1.27)
							)
						)
					)
				)
				(pin passive line
					(at 17.78 -5.08 180)
					(length 2.54)
					(name "BST"
						(effects
							(font
								(size 1.27 1.27)
							)
						)
					)
					(number "7"
						(effects
							(font
								(size 1.27 1.27)
							)
						)
					)
				)
				(pin input line
					(at 17.78 -10.16 180)
					(length 2.54)
					(name "FB"
						(effects
							(font
								(size 1.27 1.27)
							)
						)
					)
					(number "2"
						(effects
							(font
								(size 1.27 1.27)
							)
						)
					)
				)
				(pin power_in line
					(at 17.78 -15.24 180)
					(length 2.54)
					(name "PGND"
						(effects
							(font
								(size 1.27 1.27)
							)
						)
					)
					(number "4"
						(effects
							(font
								(size 1.27 1.27)
							)
						)
					)
				)
			)
		)
	(symbol "antmicroCapacitors0402:C_100n_0402"
			(pin_numbers
				(hide yes)
			)
			(pin_names
				(hide yes)
			)
			(exclude_from_sim no)
			(in_bom yes)
			(on_board yes)
			(property "Reference" "C"
				(at 20.32 -5.08 0)
				(effects
					(font
						(size 1.27 1.27)
						(thickness 0.15)
					)
					(justify left bottom)
				)
			)
			(property "Value" "C_100n_0402"
				(at 20.32 -10.16 0)
				(effects
					(font
						(size 1.27 1.27)
						(thickness 0.15)
					)
					(justify left bottom)
					(hide yes)
				)
			)
			(property "Footprint" "antmicro-footprints:C_0402_1005Metric"
				(at 20.32 -12.7 0)
				(effects
					(font
						(size 1.27 1.27)
						(thickness 0.15)
					)
					(justify left bottom)
					(hide yes)
				)
			)
			(property "Datasheet" "https://www.murata.com/products/productdetail?partno=GRM155R61H104KE14%23"
				(at 20.32 -15.24 0)
				(effects
					(font
						(size 1.27 1.27)
						(thickness 0.15)
					)
					(justify left bottom)
					(hide yes)
				)
			)
			(property "Description" "SMD Multilayer Ceramic Capacitor, 0.1 µF, 50 V, 0402 [1005 Metric], ± 10%, X5R, GRM Series"
				(at 20.32 -33.02 0)
				(effects
					(font
						(size 1.27 1.27)
					)
					(justify left bottom)
					(hide yes)
				)
			)
			(property "MPN" "GRM155R61H104KE14D"
				(at 20.32 -17.78 0)
				(effects
					(font
						(size 1.27 1.27)
						(thickness 0.15)
					)
					(justify left bottom)
					(hide yes)
				)
			)
			(property "Manufacturer" "Murata"
				(at 20.32 -20.32 0)
				(effects
					(font
						(size 1.27 1.27)
						(thickness 0.15)
					)
					(justify left bottom)
					(hide yes)
				)
			)
			(property "License" "Apache-2.0"
				(at 20.32 -22.86 0)
				(effects
					(font
						(size 1.27 1.27)
						(thickness 0.15)
					)
					(justify left bottom)
					(hide yes)
				)
			)
			(property "Author" "Antmicro"
				(at 20.32 -25.4 0)
				(effects
					(font
						(size 1.27 1.27)
						(thickness 0.15)
					)
					(justify left bottom)
					(hide yes)
				)
			)
			(property "Val" "100n"
				(at 20.32 -7.62 0)
				(effects
					(font
						(size 1.27 1.27)
						(thickness 0.15)
					)
					(justify left bottom)
				)
			)
			(property "Voltage" "50V"
				(at 20.32 -27.94 0)
				(effects
					(font
						(size 1.27 1.27)
					)
					(justify left bottom)
					(hide yes)
				)
			)
			(property "Dielectric" "X5R"
				(at 20.32 -30.48 0)
				(effects
					(font
						(size 1.27 1.27)
					)
					(justify left bottom)
					(hide yes)
				)
			)
			(property "ki_keywords" "0402, SMT, CAPACITOR, PASSIVE, CERAMIC, MLCC"
				(at 0 0 0)
				(effects
					(font
						(size 1.27 1.27)
					)
					(hide yes)
				)
			)
			(symbol "C_100n_0402_0_1"
				(polyline
					(pts
						(xy 2.032 -1.524) (xy 2.032 1.524)
					)
					(stroke
						(width 0.3048)
						(type default)
					)
					(fill
						(type none)
					)
				)
				(polyline
					(pts
						(xy 3.048 -1.524) (xy 3.048 1.524)
					)
					(stroke
						(width 0.3302)
						(type default)
					)
					(fill
						(type none)
					)
				)
			)
			(symbol "C_100n_0402_1_1"
				(pin passive line
					(at 0 0 0)
					(length 2.032)
					(name "~"
						(effects
							(font
								(size 1.27 1.27)
							)
						)
					)
					(number "1"
						(effects
							(font
								(size 1.27 1.27)
							)
						)
					)
				)
				(pin passive line
					(at 5.08 0 180)
					(length 2.032)
					(name "~"
						(effects
							(font
								(size 1.27 1.27)
							)
						)
					)
					(number "2"
						(effects
							(font
								(size 1.27 1.27)
							)
						)
					)
				)
			)
		)
	(symbol "antmicroCapacitors0402:C_10n_0402"
			(pin_numbers
				(hide yes)
			)
			(pin_names
				(hide yes)
			)
			(exclude_from_sim no)
			(in_bom yes)
			(on_board yes)
			(property "Reference" "C"
				(at 20.32 -5.08 0)
				(effects
					(font
						(size 1.27 1.27)
						(thickness 0.15)
					)
					(justify left bottom)
				)
			)
			(property "Value" "C_10n_0402"
				(at 20.32 -10.16 0)
				(effects
					(font
						(size 1.27 1.27)
						(thickness 0.15)
					)
					(justify left bottom)
					(hide yes)
				)
			)
			(property "Footprint" "antmicro-footprints:C_0402_1005Metric"
				(at 20.32 -12.7 0)
				(effects
					(font
						(size 1.27 1.27)
						(thickness 0.15)
					)
					(justify left bottom)
					(hide yes)
				)
			)
			(property "Datasheet" "https://www.murata.com/products/productdetail?partno=GRM155R71H103KA88%23"
				(at 20.32 -15.24 0)
				(effects
					(font
						(size 1.27 1.27)
						(thickness 0.15)
					)
					(justify left bottom)
					(hide yes)
				)
			)
			(property "Description" "SMD Multilayer Ceramic Capacitor, 10000 pF, 50 V, 0402 [1005 Metric], ± 10%, X7R, GRM Series"
				(at 20.32 -33.02 0)
				(effects
					(font
						(size 1.27 1.27)
					)
					(justify left bottom)
					(hide yes)
				)
			)
			(property "MPN" "GRM155R71H103KA88D"
				(at 20.32 -17.78 0)
				(effects
					(font
						(size 1.27 1.27)
						(thickness 0.15)
					)
					(justify left bottom)
					(hide yes)
				)
			)
			(property "Manufacturer" "Murata"
				(at 20.32 -20.32 0)
				(effects
					(font
						(size 1.27 1.27)
						(thickness 0.15)
					)
					(justify left bottom)
					(hide yes)
				)
			)
			(property "License" "Apache-2.0"
				(at 20.32 -22.86 0)
				(effects
					(font
						(size 1.27 1.27)
						(thickness 0.15)
					)
					(justify left bottom)
					(hide yes)
				)
			)
			(property "Author" "Antmicro"
				(at 20.32 -25.4 0)
				(effects
					(font
						(size 1.27 1.27)
						(thickness 0.15)
					)
					(justify left bottom)
					(hide yes)
				)
			)
			(property "Val" "10n"
				(at 20.32 -7.62 0)
				(effects
					(font
						(size 1.27 1.27)
						(thickness 0.15)
					)
					(justify left bottom)
				)
			)
			(property "Voltage" "50V"
				(at 20.32 -27.94 0)
				(effects
					(font
						(size 1.27 1.27)
					)
					(justify left bottom)
					(hide yes)
				)
			)
			(property "Dielectric" "X7R"
				(at 20.32 -30.48 0)
				(effects
					(font
						(size 1.27 1.27)
					)
					(justify left bottom)
					(hide yes)
				)
			)
			(property "ki_keywords" "0402, SMT, CAPACITOR, PASSIVE"
				(at 0 0 0)
				(effects
					(font
						(size 1.27 1.27)
					)
					(hide yes)
				)
			)
			(symbol "C_10n_0402_0_1"
				(polyline
					(pts
						(xy 2.032 -1.524) (xy 2.032 1.524)
					)
					(stroke
						(width 0.3048)
						(type default)
					)
					(fill
						(type none)
					)
				)
				(polyline
					(pts
						(xy 3.048 -1.524) (xy 3.048 1.524)
					)
					(stroke
						(width 0.3302)
						(type default)
					)
					(fill
						(type none)
					)
				)
			)
			(symbol "C_10n_0402_1_1"
				(pin passive line
					(at 0 0 0)
					(length 2.032)
					(name "~"
						(effects
							(font
								(size 1.27 1.27)
							)
						)
					)
					(number "1"
						(effects
							(font
								(size 1.27 1.27)
							)
						)
					)
				)
				(pin passive line
					(at 5.08 0 180)
					(length 2.032)
					(name "~"
						(effects
							(font
								(size 1.27 1.27)
							)
						)
					)
					(number "2"
						(effects
							(font
								(size 1.27 1.27)
							)
						)
					)
				)
			)
		)
	(symbol "antmicroCapacitors0402:C_10p_0402"
			(pin_numbers
				(hide yes)
			)
			(pin_names
				(hide yes)
			)
			(exclude_from_sim no)
			(in_bom yes)
			(on_board yes)
			(property "Reference" "C"
				(at 20.32 -5.08 0)
				(effects
					(font
						(size 1.27 1.27)
						(thickness 0.15)
					)
					(justify left bottom)
				)
			)
			(property "Value" "C_10p_0402"
				(at 20.32 -10.16 0)
				(effects
					(font
						(size 1.27 1.27)
						(thickness 0.15)
					)
					(justify left bottom)
					(hide yes)
				)
			)
			(property "Footprint" "antmicro-footprints:C_0402_1005Metric"
				(at 20.32 -12.7 0)
				(effects
					(font
						(size 1.27 1.27)
						(thickness 0.15)
					)
					(justify left bottom)
					(hide yes)
				)
			)
			(property "Datasheet" "https://www.murata.com/products/productdetail?partno=GCM1555C1H100GA16%23"
				(at 20.32 -15.24 0)
				(effects
					(font
						(size 1.27 1.27)
						(thickness 0.15)
					)
					(justify left bottom)
					(hide yes)
				)
			)
			(property "Description" "SMD Multilayer Ceramic Capacitor, 10 pF, 50 V, 0402 [1005 Metric], ± 2%, C0G / NP0, GCM"
				(at 20.32 -33.02 0)
				(effects
					(font
						(size 1.27 1.27)
					)
					(justify left bottom)
					(hide yes)
				)
			)
			(property "MPN" "GCM1555C1H100GA16D"
				(at 20.32 -17.78 0)
				(effects
					(font
						(size 1.27 1.27)
						(thickness 0.15)
					)
					(justify left bottom)
					(hide yes)
				)
			)
			(property "Manufacturer" "Murata"
				(at 20.32 -20.32 0)
				(effects
					(font
						(size 1.27 1.27)
						(thickness 0.15)
					)
					(justify left bottom)
					(hide yes)
				)
			)
			(property "License" "Apache-2.0"
				(at 20.32 -22.86 0)
				(effects
					(font
						(size 1.27 1.27)
						(thickness 0.15)
					)
					(justify left bottom)
					(hide yes)
				)
			)
			(property "Author" "Antmicro"
				(at 20.32 -25.4 0)
				(effects
					(font
						(size 1.27 1.27)
						(thickness 0.15)
					)
					(justify left bottom)
					(hide yes)
				)
			)
			(property "Val" "10p"
				(at 20.32 -7.62 0)
				(effects
					(font
						(size 1.27 1.27)
						(thickness 0.15)
					)
					(justify left bottom)
				)
			)
			(property "Voltage" "50V"
				(at 20.32 -27.94 0)
				(effects
					(font
						(size 1.27 1.27)
					)
					(justify left bottom)
					(hide yes)
				)
			)
			(property "Dielectric" "C0G"
				(at 20.32 -30.48 0)
				(effects
					(font
						(size 1.27 1.27)
					)
					(justify left bottom)
					(hide yes)
				)
			)
			(property "ki_keywords" "0402, SMT, CAPACITOR, PASSIVE"
				(at 0 0 0)
				(effects
					(font
						(size 1.27 1.27)
					)
					(hide yes)
				)
			)
			(symbol "C_10p_0402_0_1"
				(polyline
					(pts
						(xy 2.032 -1.524) (xy 2.032 1.524)
					)
					(stroke
						(width 0.3048)
						(type default)
					)
					(fill
						(type none)
					)
				)
				(polyline
					(pts
						(xy 3.048 -1.524) (xy 3.048 1.524)
					)
					(stroke
						(width 0.3302)
						(type default)
					)
					(fill
						(type none)
					)
				)
			)
			(symbol "C_10p_0402_1_1"
				(pin passive line
					(at 0 0 0)
					(length 2.032)
					(name "~"
						(effects
							(font
								(size 1.27 1.27)
							)
						)
					)
					(number "1"
						(effects
							(font
								(size 1.27 1.27)
							)
						)
					)
				)
				(pin passive line
					(at 5.08 0 180)
					(length 2.032)
					(name "~"
						(effects
							(font
								(size 1.27 1.27)
							)
						)
					)
					(number "2"
						(effects
							(font
								(size 1.27 1.27)
							)
						)
					)
				)
			)
		)
	(symbol "antmicroCapacitors0402:C_1u_25V_0402"
			(pin_numbers
				(hide yes)
			)
			(pin_names
				(hide yes)
			)
			(exclude_from_sim no)
			(in_bom yes)
			(on_board yes)
			(property "Reference" "C"
				(at 20.32 -5.08 0)
				(effects
					(font
						(size 1.27 1.27)
						(thickness 0.15)
					)
					(justify left bottom)
				)
			)
			(property "Value" "C_1u_25V_0402"
				(at 20.32 -10.16 0)
				(effects
					(font
						(size 1.27 1.27)
						(thickness 0.15)
					)
					(justify left bottom)
					(hide yes)
				)
			)
			(property "Footprint" "antmicro-footprints:C_0402_1005Metric"
				(at 20.32 -12.7 0)
				(effects
					(font
						(size 1.27 1.27)
						(thickness 0.15)
					)
					(justify left bottom)
					(hide yes)
				)
			)
			(property "Datasheet" "https://www.murata.com/products/productdetail?partno=GRM155R61E105KE11%23"
				(at 20.32 -15.24 0)
				(effects
					(font
						(size 1.27 1.27)
						(thickness 0.15)
					)
					(justify left bottom)
					(hide yes)
				)
			)
			(property "Description" "SMD Multilayer Ceramic Capacitor, 1 µF, 25 V, 0402 [1005 Metric], ± 10%, X5R, GRM Series"
				(at 20.32 -33.02 0)
				(effects
					(font
						(size 1.27 1.27)
					)
					(justify left bottom)
					(hide yes)
				)
			)
			(property "MPN" "GRM155R61E105KE11J"
				(at 20.32 -17.78 0)
				(effects
					(font
						(size 1.27 1.27)
						(thickness 0.15)
					)
					(justify left bottom)
					(hide yes)
				)
			)
			(property "Manufacturer" "Murata"
				(at 20.32 -20.32 0)
				(effects
					(font
						(size 1.27 1.27)
						(thickness 0.15)
					)
					(justify left bottom)
					(hide yes)
				)
			)
			(property "License" "Apache-2.0"
				(at 20.32 -22.86 0)
				(effects
					(font
						(size 1.27 1.27)
						(thickness 0.15)
					)
					(justify left bottom)
					(hide yes)
				)
			)
			(property "Author" "Antmicro"
				(at 20.32 -25.4 0)
				(effects
					(font
						(size 1.27 1.27)
						(thickness 0.15)
					)
					(justify left bottom)
					(hide yes)
				)
			)
			(property "Val" "1u"
				(at 20.32 -7.62 0)
				(effects
					(font
						(size 1.27 1.27)
						(thickness 0.15)
					)
					(justify left bottom)
				)
			)
			(property "Voltage" "25V"
				(at 20.32 -27.94 0)
				(effects
					(font
						(size 1.27 1.27)
					)
					(justify left bottom)
					(hide yes)
				)
			)
			(property "Dielectric" "X5R"
				(at 20.32 -30.48 0)
				(effects
					(font
						(size 1.27 1.27)
					)
					(justify left bottom)
					(hide yes)
				)
			)
			(property "ki_keywords" "0402, SMT, CAPACITOR, PASSIVE, CERAMIC"
				(at 0 0 0)
				(effects
					(font
						(size 1.27 1.27)
					)
					(hide yes)
				)
			)
			(symbol "C_1u_25V_0402_0_1"
				(polyline
					(pts
						(xy 2.032 -1.524) (xy 2.032 1.524)
					)
					(stroke
						(width 0.3048)
						(type default)
					)
					(fill
						(type none)
					)
				)
				(polyline
					(pts
						(xy 3.048 -1.524) (xy 3.048 1.524)
					)
					(stroke
						(width 0.3302)
						(type default)
					)
					(fill
						(type none)
					)
				)
			)
			(symbol "C_1u_25V_0402_1_1"
				(pin passive line
					(at 0 0 0)
					(length 2.032)
					(name "~"
						(effects
							(font
								(size 1.27 1.27)
							)
						)
					)
					(number "1"
						(effects
							(font
								(size 1.27 1.27)
							)
						)
					)
				)
				(pin passive line
					(at 5.08 0 180)
					(length 2.032)
					(name "~"
						(effects
							(font
								(size 1.27 1.27)
							)
						)
					)
					(number "2"
						(effects
							(font
								(size 1.27 1.27)
							)
						)
					)
				)
			)
		)
	(symbol "antmicroCapacitors0402:C_220n_16V_0402"
			(pin_numbers
				(hide yes)
			)
			(pin_names
				(hide yes)
			)
			(exclude_from_sim no)
			(in_bom yes)
			(on_board yes)
			(property "Reference" "C"
				(at 20.32 -5.08 0)
				(effects
					(font
						(size 1.27 1.27)
						(thickness 0.15)
					)
					(justify left bottom)
				)
			)
			(property "Value" "C_220n_16V_0402"
				(at 20.32 -10.16 0)
				(effects
					(font
						(size 1.27 1.27)
						(thickness 0.15)
					)
					(justify left bottom)
					(hide yes)
				)
			)
			(property "Footprint" "antmicro-footprints:C_0402_1005Metric"
				(at 20.32 -12.7 0)
				(effects
					(font
						(size 1.27 1.27)
						(thickness 0.15)
					)
					(justify left bottom)
					(hide yes)
				)
			)
			(property "Datasheet" "https://www.murata.com/products/productdetail?partno=GRM155R71C224KA12%23"
				(at 20.32 -15.24 0)
				(effects
					(font
						(size 1.27 1.27)
						(thickness 0.15)
					)
					(justify left bottom)
					(hide yes)
				)
			)
			(property "Description" "SMD Multilayer Ceramic Capacitor, 0.22 µF, 16 V, 0402 [1005 Metric], ± 10%, X7R, GRM Series"
				(at 20.32 -33.02 0)
				(effects
					(font
						(size 1.27 1.27)
					)
					(justify left bottom)
					(hide yes)
				)
			)
			(property "MPN" "GRM155R71C224KA12D"
				(at 20.32 -17.78 0)
				(effects
					(font
						(size 1.27 1.27)
						(thickness 0.15)
					)
					(justify left bottom)
					(hide yes)
				)
			)
			(property "Manufacturer" "Murata"
				(at 20.32 -20.32 0)
				(effects
					(font
						(size 1.27 1.27)
						(thickness 0.15)
					)
					(justify left bottom)
					(hide yes)
				)
			)
			(property "License" "Apache-2.0"
				(at 20.32 -22.86 0)
				(effects
					(font
						(size 1.27 1.27)
						(thickness 0.15)
					)
					(justify left bottom)
					(hide yes)
				)
			)
			(property "Author" "Antmicro"
				(at 20.32 -25.4 0)
				(effects
					(font
						(size 1.27 1.27)
						(thickness 0.15)
					)
					(justify left bottom)
					(hide yes)
				)
			)
			(property "Val" "220n"
				(at 20.32 -7.62 0)
				(effects
					(font
						(size 1.27 1.27)
						(thickness 0.15)
					)
					(justify left bottom)
				)
			)
			(property "Voltage" "16V"
				(at 20.32 -27.94 0)
				(effects
					(font
						(size 1.27 1.27)
					)
					(justify left bottom)
					(hide yes)
				)
			)
			(property "Dielectric" "X7R"
				(at 20.32 -30.48 0)
				(effects
					(font
						(size 1.27 1.27)
					)
					(justify left bottom)
					(hide yes)
				)
			)
			(property "ki_keywords" "0402, SMT, CAPACITOR, PASSIVE, CERAMIC"
				(at 0 0 0)
				(effects
					(font
						(size 1.27 1.27)
					)
					(hide yes)
				)
			)
			(symbol "C_220n_16V_0402_0_1"
				(polyline
					(pts
						(xy 2.032 -1.524) (xy 2.032 1.524)
					)
					(stroke
						(width 0.3048)
						(type default)
					)
					(fill
						(type none)
					)
				)
				(polyline
					(pts
						(xy 3.048 -1.524) (xy 3.048 1.524)
					)
					(stroke
						(width 0.3302)
						(type default)
					)
					(fill
						(type none)
					)
				)
			)
			(symbol "C_220n_16V_0402_1_1"
				(pin passive line
					(at 0 0 0)
					(length 2.032)
					(name "~"
						(effects
							(font
								(size 1.27 1.27)
							)
						)
					)
					(number "1"
						(effects
							(font
								(size 1.27 1.27)
							)
						)
					)
				)
				(pin passive line
					(at 5.08 0 180)
					(length 2.032)
					(name "~"
						(effects
							(font
								(size 1.27 1.27)
							)
						)
					)
					(number "2"
						(effects
							(font
								(size 1.27 1.27)
							)
						)
					)
				)
			)
		)
	(symbol "antmicroCapacitors0402:C_33p_0402"
			(pin_numbers
				(hide yes)
			)
			(pin_names
				(hide yes)
			)
			(exclude_from_sim no)
			(in_bom yes)
			(on_board yes)
			(property "Reference" "C"
				(at 20.32 -5.08 0)
				(effects
					(font
						(size 1.27 1.27)
						(thickness 0.15)
					)
					(justify left bottom)
				)
			)
			(property "Value" "C_33p_0402"
				(at 20.32 -10.16 0)
				(effects
					(font
						(size 1.27 1.27)
						(thickness 0.15)
					)
					(justify left bottom)
					(hide yes)
				)
			)
			(property "Footprint" "antmicro-footprints:C_0402_1005Metric"
				(at 20.32 -12.7 0)
				(effects
					(font
						(size 1.27 1.27)
						(thickness 0.15)
					)
					(justify left bottom)
					(hide yes)
				)
			)
			(property "Datasheet" "https://spicat.kyocera-avx.com/product/mlcc/chartview/04025A330FAT2A/"
				(at 20.32 -15.24 0)
				(effects
					(font
						(size 1.27 1.27)
						(thickness 0.15)
					)
					(justify left bottom)
					(hide yes)
				)
			)
			(property "Description" "SMD Multilayer Ceramic Capacitor, 33 pF, 50 V, 0402 [1005 Metric], ± 5%, C0G / NP0, MC"
				(at 20.32 -33.02 0)
				(effects
					(font
						(size 1.27 1.27)
					)
					(justify left bottom)
					(hide yes)
				)
			)
			(property "MPN" "04025A330FAT2A"
				(at 20.32 -17.78 0)
				(effects
					(font
						(size 1.27 1.27)
						(thickness 0.15)
					)
					(justify left bottom)
					(hide yes)
				)
			)
			(property "Manufacturer" "KYOCERA AVX"
				(at 20.32 -20.32 0)
				(effects
					(font
						(size 1.27 1.27)
						(thickness 0.15)
					)
					(justify left bottom)
					(hide yes)
				)
			)
			(property "License" "Apache-2.0"
				(at 20.32 -22.86 0)
				(effects
					(font
						(size 1.27 1.27)
						(thickness 0.15)
					)
					(justify left bottom)
					(hide yes)
				)
			)
			(property "Author" "Antmicro"
				(at 20.32 -25.4 0)
				(effects
					(font
						(size 1.27 1.27)
						(thickness 0.15)
					)
					(justify left bottom)
					(hide yes)
				)
			)
			(property "Val" "33p"
				(at 20.32 -7.62 0)
				(effects
					(font
						(size 1.27 1.27)
						(thickness 0.15)
					)
					(justify left bottom)
				)
			)
			(property "Voltage" ""
				(at 20.32 -27.94 0)
				(effects
					(font
						(size 1.27 1.27)
					)
					(justify left bottom)
					(hide yes)
				)
			)
			(property "Dielectric" ""
				(at 20.32 -30.48 0)
				(effects
					(font
						(size 1.27 1.27)
					)
					(justify left bottom)
					(hide yes)
				)
			)
			(property "ki_keywords" "0402, SMT, CAPACITOR, PASSIVE"
				(at 0 0 0)
				(effects
					(font
						(size 1.27 1.27)
					)
					(hide yes)
				)
			)
			(symbol "C_33p_0402_0_1"
				(polyline
					(pts
						(xy 2.032 -1.524) (xy 2.032 1.524)
					)
					(stroke
						(width 0.3048)
						(type default)
					)
					(fill
						(type none)
					)
				)
				(polyline
					(pts
						(xy 3.048 -1.524) (xy 3.048 1.524)
					)
					(stroke
						(width 0.3302)
						(type default)
					)
					(fill
						(type none)
					)
				)
			)
			(symbol "C_33p_0402_1_1"
				(pin passive line
					(at 0 0 0)
					(length 2.032)
					(name "~"
						(effects
							(font
								(size 1.27 1.27)
							)
						)
					)
					(number "1"
						(effects
							(font
								(size 1.27 1.27)
							)
						)
					)
				)
				(pin passive line
					(at 5.08 0 180)
					(length 2.032)
					(name "~"
						(effects
							(font
								(size 1.27 1.27)
							)
						)
					)
					(number "2"
						(effects
							(font
								(size 1.27 1.27)
							)
						)
					)
				)
			)
		)
	(symbol "antmicroCapacitors0402:C_470p_0402"
			(pin_numbers
				(hide yes)
			)
			(pin_names
				(hide yes)
			)
			(exclude_from_sim no)
			(in_bom yes)
			(on_board yes)
			(property "Reference" "C"
				(at 20.32 -5.08 0)
				(effects
					(font
						(size 1.27 1.27)
						(thickness 0.15)
					)
					(justify left bottom)
				)
			)
			(property "Value" "C_470p_0402"
				(at 20.32 -10.16 0)
				(effects
					(font
						(size 1.27 1.27)
						(thickness 0.15)
					)
					(justify left bottom)
					(hide yes)
				)
			)
			(property "Footprint" "antmicro-footprints:C_0402_1005Metric"
				(at 20.32 -12.7 0)
				(effects
					(font
						(size 1.27 1.27)
						(thickness 0.15)
					)
					(justify left bottom)
					(hide yes)
				)
			)
			(property "Datasheet" "https://www.passivecomponent.com/wp-content/uploads/datasheet/WTC_MLCC_General_Purpose.pdf"
				(at 20.32 -15.24 0)
				(effects
					(font
						(size 1.27 1.27)
						(thickness 0.15)
					)
					(justify left bottom)
					(hide yes)
				)
			)
			(property "Description" "SMD Multilayer Ceramic Capacitor, General Purpose, 470 pF, 25 V, 0402 [1005 Metric], ± 10%, X7R"
				(at 20.32 -33.02 0)
				(effects
					(font
						(size 1.27 1.27)
					)
					(justify left bottom)
					(hide yes)
				)
			)
			(property "MPN" "0402B471K250CT"
				(at 20.32 -17.78 0)
				(effects
					(font
						(size 1.27 1.27)
						(thickness 0.15)
					)
					(justify left bottom)
					(hide yes)
				)
			)
			(property "Manufacturer" "Walsin"
				(at 20.32 -20.32 0)
				(effects
					(font
						(size 1.27 1.27)
						(thickness 0.15)
					)
					(justify left bottom)
					(hide yes)
				)
			)
			(property "License" "Apache-2.0"
				(at 20.32 -22.86 0)
				(effects
					(font
						(size 1.27 1.27)
						(thickness 0.15)
					)
					(justify left bottom)
					(hide yes)
				)
			)
			(property "Author" "Antmicro"
				(at 20.32 -25.4 0)
				(effects
					(font
						(size 1.27 1.27)
						(thickness 0.15)
					)
					(justify left bottom)
					(hide yes)
				)
			)
			(property "Val" "470p"
				(at 20.32 -7.62 0)
				(effects
					(font
						(size 1.27 1.27)
						(thickness 0.15)
					)
					(justify left bottom)
				)
			)
			(property "Voltage" "25V"
				(at 20.32 -27.94 0)
				(effects
					(font
						(size 1.27 1.27)
					)
					(justify left bottom)
					(hide yes)
				)
			)
			(property "Dielectric" "X7R"
				(at 20.32 -30.48 0)
				(effects
					(font
						(size 1.27 1.27)
					)
					(justify left bottom)
					(hide yes)
				)
			)
			(property "ki_keywords" "0402, SMT, CAPACITOR, PASSIVE, MLCC"
				(at 0 0 0)
				(effects
					(font
						(size 1.27 1.27)
					)
					(hide yes)
				)
			)
			(symbol "C_470p_0402_0_1"
				(polyline
					(pts
						(xy 2.032 -1.524) (xy 2.032 1.524)
					)
					(stroke
						(width 0.3048)
						(type default)
					)
					(fill
						(type none)
					)
				)
				(polyline
					(pts
						(xy 3.048 -1.524) (xy 3.048 1.524)
					)
					(stroke
						(width 0.3302)
						(type default)
					)
					(fill
						(type none)
					)
				)
			)
			(symbol "C_470p_0402_1_1"
				(pin passive line
					(at 0 0 0)
					(length 2.032)
					(name "~"
						(effects
							(font
								(size 1.27 1.27)
							)
						)
					)
					(number "1"
						(effects
							(font
								(size 1.27 1.27)
							)
						)
					)
				)
				(pin passive line
					(at 5.08 0 180)
					(length 2.032)
					(name "~"
						(effects
							(font
								(size 1.27 1.27)
							)
						)
					)
					(number "2"
						(effects
							(font
								(size 1.27 1.27)
							)
						)
					)
				)
			)
		)
	(symbol "antmicroCapacitors0402:C_5p6_0402"
			(pin_numbers
				(hide yes)
			)
			(pin_names
				(hide yes)
			)
			(exclude_from_sim no)
			(in_bom yes)
			(on_board yes)
			(property "Reference" "C"
				(at 20.32 -5.08 0)
				(effects
					(font
						(size 1.27 1.27)
						(thickness 0.15)
					)
					(justify left bottom)
				)
			)
			(property "Value" "C_5p6_0402"
				(at 20.32 -10.16 0)
				(effects
					(font
						(size 1.27 1.27)
						(thickness 0.15)
					)
					(justify left bottom)
					(hide yes)
				)
			)
			(property "Footprint" "antmicro-footprints:C_0402_1005Metric"
				(at 20.32 -12.7 0)
				(effects
					(font
						(size 1.27 1.27)
						(thickness 0.15)
					)
					(justify left bottom)
					(hide yes)
				)
			)
			(property "Datasheet" "https://www.mouser.com/datasheet/3/76/2/GCM1555C1H5R6BA16_01A.pdf"
				(at 20.32 -15.24 0)
				(effects
					(font
						(size 1.27 1.27)
						(thickness 0.15)
					)
					(justify left bottom)
					(hide yes)
				)
			)
			(property "Description" "Multilayer Ceramic Capacitors MLCC - SMD/SMT 5.6 pF 50 VDC 0.1 pF 0402 C0G (NP0) AEC-Q200"
				(at 20.32 -33.02 0)
				(effects
					(font
						(size 1.27 1.27)
					)
					(justify left bottom)
					(hide yes)
				)
			)
			(property "MPN" "GCM1555C1H5R6BA16D"
				(at 20.32 -17.78 0)
				(effects
					(font
						(size 1.27 1.27)
						(thickness 0.15)
					)
					(justify left bottom)
					(hide yes)
				)
			)
			(property "Manufacturer" "Murata"
				(at 20.32 -20.32 0)
				(effects
					(font
						(size 1.27 1.27)
						(thickness 0.15)
					)
					(justify left bottom)
					(hide yes)
				)
			)
			(property "License" "Apache-2.0"
				(at 20.32 -22.86 0)
				(effects
					(font
						(size 1.27 1.27)
						(thickness 0.15)
					)
					(justify left bottom)
					(hide yes)
				)
			)
			(property "Author" "Antmicro"
				(at 20.32 -25.4 0)
				(effects
					(font
						(size 1.27 1.27)
						(thickness 0.15)
					)
					(justify left bottom)
					(hide yes)
				)
			)
			(property "Val" "5p6"
				(at 20.32 -7.62 0)
				(effects
					(font
						(size 1.27 1.27)
						(thickness 0.15)
					)
					(justify left bottom)
				)
			)
			(property "Voltage" "50V"
				(at 20.32 -27.94 0)
				(effects
					(font
						(size 1.27 1.27)
					)
					(justify left bottom)
					(hide yes)
				)
			)
			(property "Dielectric" "C0G"
				(at 20.32 -30.48 0)
				(effects
					(font
						(size 1.27 1.27)
					)
					(justify left bottom)
					(hide yes)
				)
			)
			(property "ki_keywords" "0402, SMT, CAPACITOR, PASSIVE, CERAMIC, MLCC"
				(at 0 0 0)
				(effects
					(font
						(size 1.27 1.27)
					)
					(hide yes)
				)
			)
			(symbol "C_5p6_0402_0_1"
				(polyline
					(pts
						(xy 2.032 -1.524) (xy 2.032 1.524)
					)
					(stroke
						(width 0.3048)
						(type default)
					)
					(fill
						(type none)
					)
				)
				(polyline
					(pts
						(xy 3.048 -1.524) (xy 3.048 1.524)
					)
					(stroke
						(width 0.3302)
						(type default)
					)
					(fill
						(type none)
					)
				)
			)
			(symbol "C_5p6_0402_1_1"
				(pin passive line
					(at 0 0 0)
					(length 2.032)
					(name "~"
						(effects
							(font
								(size 1.27 1.27)
							)
						)
					)
					(number "1"
						(effects
							(font
								(size 1.27 1.27)
							)
						)
					)
				)
				(pin passive line
					(at 5.08 0 180)
					(length 2.032)
					(name "~"
						(effects
							(font
								(size 1.27 1.27)
							)
						)
					)
					(number "2"
						(effects
							(font
								(size 1.27 1.27)
							)
						)
					)
				)
			)
		)
	(symbol "antmicroCapacitors0603:C_10u_10V_X7R_0603"
			(pin_numbers
				(hide yes)
			)
			(pin_names
				(hide yes)
			)
			(exclude_from_sim no)
			(in_bom yes)
			(on_board yes)
			(property "Reference" "C"
				(at 15.24 -5.08 0)
				(effects
					(font
						(size 1.27 1.27)
						(thickness 0.15)
					)
					(justify left bottom)
				)
			)
			(property "Value" "C_10u_10V_X7R_0603"
				(at 15.24 -10.16 0)
				(effects
					(font
						(size 1.27 1.27)
						(thickness 0.15)
					)
					(justify left bottom)
					(hide yes)
				)
			)
			(property "Footprint" "antmicro-footprints:C_0603_1608Metric"
				(at 15.24 -12.7 0)
				(effects
					(font
						(size 1.27 1.27)
						(thickness 0.15)
					)
					(justify left bottom)
					(hide yes)
				)
			)
			(property "Datasheet" "https://www.murata.com/products/productdetail?partno=GRM188Z71A106KA73%23"
				(at 15.24 -15.24 0)
				(effects
					(font
						(size 1.27 1.27)
						(thickness 0.15)
					)
					(justify left bottom)
					(hide yes)
				)
			)
			(property "Description" "SMD Multilayer Ceramic Capacitor,  10µF, 10V, 0603, ±10%, X7R"
				(at 15.24 -33.02 0)
				(effects
					(font
						(size 1.27 1.27)
					)
					(justify left bottom)
					(hide yes)
				)
			)
			(property "MPN" "GRM188Z71A106KA73D"
				(at 15.24 -17.78 0)
				(effects
					(font
						(size 1.27 1.27)
						(thickness 0.15)
					)
					(justify left bottom)
					(hide yes)
				)
			)
			(property "Val" "10u"
				(at 15.24 -7.62 0)
				(effects
					(font
						(size 1.27 1.27)
						(thickness 0.15)
					)
					(justify left bottom)
				)
			)
			(property "Voltage" "10V"
				(at 15.24 -20.32 0)
				(effects
					(font
						(size 1.27 1.27)
						(thickness 0.15)
					)
					(justify left bottom)
					(hide yes)
				)
			)
			(property "Dielectric" "X7R"
				(at 15.24 -22.86 0)
				(effects
					(font
						(size 1.27 1.27)
						(thickness 0.15)
					)
					(justify left bottom)
					(hide yes)
				)
			)
			(property "Manufacturer" "Murata"
				(at 15.24 -25.4 0)
				(effects
					(font
						(size 1.27 1.27)
						(thickness 0.15)
					)
					(justify left bottom)
					(hide yes)
				)
			)
			(property "License" "Apache-2.0"
				(at 15.24 -27.94 0)
				(effects
					(font
						(size 1.27 1.27)
						(thickness 0.15)
					)
					(justify left bottom)
					(hide yes)
				)
			)
			(property "Author" "Antmicro"
				(at 15.24 -30.48 0)
				(effects
					(font
						(size 1.27 1.27)
						(thickness 0.15)
					)
					(justify left bottom)
					(hide yes)
				)
			)
			(property "ki_keywords" "SMT, CAPACITOR, PASSIVE"
				(at 0 0 0)
				(effects
					(font
						(size 1.27 1.27)
					)
					(hide yes)
				)
			)
			(symbol "C_10u_10V_X7R_0603_0_1"
				(polyline
					(pts
						(xy 2.032 -1.524) (xy 2.032 1.524)
					)
					(stroke
						(width 0.3048)
						(type default)
					)
					(fill
						(type none)
					)
				)
				(polyline
					(pts
						(xy 3.048 -1.524) (xy 3.048 1.524)
					)
					(stroke
						(width 0.3302)
						(type default)
					)
					(fill
						(type none)
					)
				)
			)
			(symbol "C_10u_10V_X7R_0603_1_1"
				(pin passive line
					(at 0 0 0)
					(length 2.032)
					(name "~"
						(effects
							(font
								(size 1.27 1.27)
							)
						)
					)
					(number "1"
						(effects
							(font
								(size 1.27 1.27)
							)
						)
					)
				)
				(pin passive line
					(at 5.08 0 180)
					(length 2.032)
					(name "~"
						(effects
							(font
								(size 1.27 1.27)
							)
						)
					)
					(number "2"
						(effects
							(font
								(size 1.27 1.27)
							)
						)
					)
				)
			)
		)
	(symbol "antmicroCapacitors0603:C_22u_16V_0603"
			(pin_numbers
				(hide yes)
			)
			(pin_names
				(hide yes)
			)
			(exclude_from_sim no)
			(in_bom yes)
			(on_board yes)
			(property "Reference" "C"
				(at 20.32 -5.08 0)
				(effects
					(font
						(size 1.27 1.27)
						(thickness 0.15)
					)
					(justify left bottom)
				)
			)
			(property "Value" "C_22u_16V_0603"
				(at 20.32 -10.16 0)
				(effects
					(font
						(size 1.27 1.27)
						(thickness 0.15)
					)
					(justify left bottom)
					(hide yes)
				)
			)
			(property "Footprint" "antmicro-footprints:C_0603_1608Metric_EIA"
				(at 20.32 -12.7 0)
				(effects
					(font
						(size 1.27 1.27)
						(thickness 0.15)
					)
					(justify left bottom)
					(hide yes)
				)
			)
			(property "Datasheet" "https://product.samsungsem.com/mlcc/CL10A226MO7JZN.do"
				(at 20.32 -15.24 0)
				(effects
					(font
						(size 1.27 1.27)
						(thickness 0.15)
					)
					(justify left bottom)
					(hide yes)
				)
			)
			(property "Description" "SMD Multilayer Ceramic Capacitor"
				(at 20.32 -33.02 0)
				(effects
					(font
						(size 1.27 1.27)
					)
					(justify left bottom)
					(hide yes)
				)
			)
			(property "MPN" "CL10A226MO7JZNC"
				(at 20.32 -17.78 0)
				(effects
					(font
						(size 1.27 1.27)
						(thickness 0.15)
					)
					(justify left bottom)
					(hide yes)
				)
			)
			(property "Manufacturer" "Samsung Electro-Mechanics"
				(at 20.32 -20.32 0)
				(effects
					(font
						(size 1.27 1.27)
						(thickness 0.15)
					)
					(justify left bottom)
					(hide yes)
				)
			)
			(property "License" "Apache-2.0"
				(at 20.32 -22.86 0)
				(effects
					(font
						(size 1.27 1.27)
						(thickness 0.15)
					)
					(justify left bottom)
					(hide yes)
				)
			)
			(property "Author" "Antmicro"
				(at 20.32 -25.4 0)
				(effects
					(font
						(size 1.27 1.27)
						(thickness 0.15)
					)
					(justify left bottom)
					(hide yes)
				)
			)
			(property "Val" "22u"
				(at 20.32 -7.62 0)
				(effects
					(font
						(size 1.27 1.27)
						(thickness 0.15)
					)
					(justify left bottom)
				)
			)
			(property "Voltage" "16V"
				(at 20.32 -27.94 0)
				(effects
					(font
						(size 1.27 1.27)
					)
					(justify left bottom)
					(hide yes)
				)
			)
			(property "Dielectric" ""
				(at 20.32 -30.48 0)
				(effects
					(font
						(size 1.27 1.27)
					)
					(justify left bottom)
					(hide yes)
				)
			)
			(property "ki_keywords" "0603, SMT, CAPACITOR, PASSIVE, CERAMIC"
				(at 0 0 0)
				(effects
					(font
						(size 1.27 1.27)
					)
					(hide yes)
				)
			)
			(symbol "C_22u_16V_0603_0_1"
				(polyline
					(pts
						(xy 2.032 -1.524) (xy 2.032 1.524)
					)
					(stroke
						(width 0.3048)
						(type default)
					)
					(fill
						(type none)
					)
				)
				(polyline
					(pts
						(xy 3.048 -1.524) (xy 3.048 1.524)
					)
					(stroke
						(width 0.3302)
						(type default)
					)
					(fill
						(type none)
					)
				)
			)
			(symbol "C_22u_16V_0603_1_1"
				(pin passive line
					(at 0 0 0)
					(length 2.032)
					(name "~"
						(effects
							(font
								(size 1.27 1.27)
							)
						)
					)
					(number "1"
						(effects
							(font
								(size 1.27 1.27)
							)
						)
					)
				)
				(pin passive line
					(at 5.08 0 180)
					(length 2.032)
					(name "~"
						(effects
							(font
								(size 1.27 1.27)
							)
						)
					)
					(number "2"
						(effects
							(font
								(size 1.27 1.27)
							)
						)
					)
				)
			)
		)
	(symbol "antmicroCapacitors0603:C_47u_0603"
			(pin_numbers
				(hide yes)
			)
			(pin_names
				(hide yes)
			)
			(exclude_from_sim no)
			(in_bom yes)
			(on_board yes)
			(property "Reference" "C"
				(at 20.32 -5.08 0)
				(effects
					(font
						(size 1.27 1.27)
						(thickness 0.15)
					)
					(justify left bottom)
				)
			)
			(property "Value" "C_47u_0603"
				(at 20.32 -10.16 0)
				(effects
					(font
						(size 1.27 1.27)
						(thickness 0.15)
					)
					(justify left bottom)
					(hide yes)
				)
			)
			(property "Footprint" "antmicro-footprints:C_0603_1608Metric"
				(at 20.32 -12.7 0)
				(effects
					(font
						(size 1.27 1.27)
						(thickness 0.15)
					)
					(justify left bottom)
					(hide yes)
				)
			)
			(property "Datasheet" "https://www.murata.com/products/productdetail?partno=GRM188R60J476ME15%23"
				(at 20.32 -15.24 0)
				(effects
					(font
						(size 1.27 1.27)
						(thickness 0.15)
					)
					(justify left bottom)
					(hide yes)
				)
			)
			(property "Description" "SMD Multilayer Ceramic Capacitor, 47 µF, 6.3 V, 0603 [1608 Metric], ± 20%, X5R, GRM Series"
				(at 20.32 -33.02 0)
				(effects
					(font
						(size 1.27 1.27)
					)
					(justify left bottom)
					(hide yes)
				)
			)
			(property "MPN" "GRM188R60J476ME15D"
				(at 20.32 -17.78 0)
				(effects
					(font
						(size 1.27 1.27)
						(thickness 0.15)
					)
					(justify left bottom)
					(hide yes)
				)
			)
			(property "Manufacturer" "Murata"
				(at 20.32 -20.32 0)
				(effects
					(font
						(size 1.27 1.27)
						(thickness 0.15)
					)
					(justify left bottom)
					(hide yes)
				)
			)
			(property "License" "Apache-2.0"
				(at 20.32 -22.86 0)
				(effects
					(font
						(size 1.27 1.27)
						(thickness 0.15)
					)
					(justify left bottom)
					(hide yes)
				)
			)
			(property "Author" "Antmicro"
				(at 20.32 -25.4 0)
				(effects
					(font
						(size 1.27 1.27)
						(thickness 0.15)
					)
					(justify left bottom)
					(hide yes)
				)
			)
			(property "Val" "47u"
				(at 20.32 -7.62 0)
				(effects
					(font
						(size 1.27 1.27)
						(thickness 0.15)
					)
					(justify left bottom)
				)
			)
			(property "Voltage" ""
				(at 20.32 -27.94 0)
				(effects
					(font
						(size 1.27 1.27)
					)
					(justify left bottom)
					(hide yes)
				)
			)
			(property "Dielectric" ""
				(at 20.32 -30.48 0)
				(effects
					(font
						(size 1.27 1.27)
					)
					(justify left bottom)
					(hide yes)
				)
			)
			(property "ki_keywords" "0603, SMT, CAPACITOR, PASSIVE, CERAMIC, MLCC"
				(at 0 0 0)
				(effects
					(font
						(size 1.27 1.27)
					)
					(hide yes)
				)
			)
			(symbol "C_47u_0603_0_1"
				(polyline
					(pts
						(xy 2.032 -1.524) (xy 2.032 1.524)
					)
					(stroke
						(width 0.3048)
						(type default)
					)
					(fill
						(type none)
					)
				)
				(polyline
					(pts
						(xy 3.048 -1.524) (xy 3.048 1.524)
					)
					(stroke
						(width 0.3302)
						(type default)
					)
					(fill
						(type none)
					)
				)
			)
			(symbol "C_47u_0603_1_1"
				(pin passive line
					(at 0 0 0)
					(length 2.032)
					(name "~"
						(effects
							(font
								(size 1.27 1.27)
							)
						)
					)
					(number "1"
						(effects
							(font
								(size 1.27 1.27)
							)
						)
					)
				)
				(pin passive line
					(at 5.08 0 180)
					(length 2.032)
					(name "~"
						(effects
							(font
								(size 1.27 1.27)
							)
						)
					)
					(number "2"
						(effects
							(font
								(size 1.27 1.27)
							)
						)
					)
				)
			)
		)
	(symbol "antmicroCapacitorsmisc:C_100u_0805"
			(pin_numbers
				(hide yes)
			)
			(pin_names
				(hide yes)
			)
			(exclude_from_sim no)
			(in_bom yes)
			(on_board yes)
			(property "Reference" "C"
				(at 20.32 -5.08 0)
				(effects
					(font
						(size 1.27 1.27)
						(thickness 0.15)
					)
					(justify left bottom)
				)
			)
			(property "Value" "C_100u_0805"
				(at 20.32 -10.16 0)
				(effects
					(font
						(size 1.27 1.27)
						(thickness 0.15)
					)
					(justify left bottom)
					(hide yes)
				)
			)
			(property "Footprint" "antmicro-footprints:C_0805_2012Metric"
				(at 20.32 -12.7 0)
				(effects
					(font
						(size 1.27 1.27)
						(thickness 0.15)
					)
					(justify left bottom)
					(hide yes)
				)
			)
			(property "Datasheet" "https://www.murata.com/products/productdetail?partno=GRM21BR60J107ME15%23"
				(at 20.32 -15.24 0)
				(effects
					(font
						(size 1.27 1.27)
						(thickness 0.15)
					)
					(justify left bottom)
					(hide yes)
				)
			)
			(property "Description" "SMD Multilayer Ceramic Capacitor, 100 µF, 6.3 V, 0805 [2012 Metric], ± 20%, X5R, GRM Series"
				(at 20.32 -33.02 0)
				(effects
					(font
						(size 1.27 1.27)
					)
					(justify left bottom)
					(hide yes)
				)
			)
			(property "MPN" "GRM21BR60J107ME15L"
				(at 20.32 -17.78 0)
				(effects
					(font
						(size 1.27 1.27)
						(thickness 0.15)
					)
					(justify left bottom)
					(hide yes)
				)
			)
			(property "Manufacturer" "Murata"
				(at 20.32 -20.32 0)
				(effects
					(font
						(size 1.27 1.27)
						(thickness 0.15)
					)
					(justify left bottom)
					(hide yes)
				)
			)
			(property "License" "Apache-2.0"
				(at 20.32 -22.86 0)
				(effects
					(font
						(size 1.27 1.27)
						(thickness 0.15)
					)
					(justify left bottom)
					(hide yes)
				)
			)
			(property "Author" "Antmicro"
				(at 20.32 -25.4 0)
				(effects
					(font
						(size 1.27 1.27)
						(thickness 0.15)
					)
					(justify left bottom)
					(hide yes)
				)
			)
			(property "Val" "100u"
				(at 20.32 -7.62 0)
				(effects
					(font
						(size 1.27 1.27)
						(thickness 0.15)
					)
					(justify left bottom)
				)
			)
			(property "Voltage" ""
				(at 20.32 -27.94 0)
				(effects
					(font
						(size 1.27 1.27)
					)
					(justify left bottom)
					(hide yes)
				)
			)
			(property "Dielectric" ""
				(at 20.32 -30.48 0)
				(effects
					(font
						(size 1.27 1.27)
					)
					(justify left bottom)
					(hide yes)
				)
			)
			(property "Public" "False"
				(at 20.32 -33.02 0)
				(effects
					(font
						(size 1.27 1.27)
					)
					(justify left bottom)
					(hide yes)
				)
			)
			(property "ki_keywords" "0805, SMT, CAPACITOR, PASSIVE"
				(at 0 0 0)
				(effects
					(font
						(size 1.27 1.27)
					)
					(hide yes)
				)
			)
			(symbol "C_100u_0805_0_1"
				(polyline
					(pts
						(xy 2.032 -1.524) (xy 2.032 1.524)
					)
					(stroke
						(width 0.3048)
						(type default)
					)
					(fill
						(type none)
					)
				)
				(polyline
					(pts
						(xy 3.048 -1.524) (xy 3.048 1.524)
					)
					(stroke
						(width 0.3302)
						(type default)
					)
					(fill
						(type none)
					)
				)
			)
			(symbol "C_100u_0805_1_1"
				(pin passive line
					(at 0 0 0)
					(length 2.032)
					(name "~"
						(effects
							(font
								(size 1.27 1.27)
							)
						)
					)
					(number "1"
						(effects
							(font
								(size 1.27 1.27)
							)
						)
					)
				)
				(pin passive line
					(at 5.08 0 180)
					(length 2.032)
					(name "~"
						(effects
							(font
								(size 1.27 1.27)
							)
						)
					)
					(number "2"
						(effects
							(font
								(size 1.27 1.27)
							)
						)
					)
				)
			)
		)
	(symbol "antmicroCapacitorsmisc:C_220u_1206_6V3"
			(pin_numbers
				(hide yes)
			)
			(pin_names
				(hide yes)
			)
			(exclude_from_sim no)
			(in_bom yes)
			(on_board yes)
			(property "Reference" "C"
				(at 20.32 -5.08 0)
				(effects
					(font
						(size 1.27 1.27)
						(thickness 0.15)
					)
					(justify left bottom)
				)
			)
			(property "Value" "C_220u_1206_6V3"
				(at 20.32 -10.16 0)
				(effects
					(font
						(size 1.27 1.27)
						(thickness 0.15)
					)
					(justify left bottom)
					(hide yes)
				)
			)
			(property "Footprint" "antmicro-footprints:C_1206_3216Metric"
				(at 20.32 -12.7 0)
				(effects
					(font
						(size 1.27 1.27)
						(thickness 0.15)
					)
					(justify left bottom)
					(hide yes)
				)
			)
			(property "Datasheet" "https://www.murata.com/products/productdetail?partno=GRM31CR60J227ME11%23"
				(at 20.32 -15.24 0)
				(effects
					(font
						(size 1.27 1.27)
						(thickness 0.15)
					)
					(justify left bottom)
					(hide yes)
				)
			)
			(property "Description" "SMD Multilayer Ceramic Capacitor, 220 µF, 6.3 V, 1206 [3216 Metric], ± 20%, X5R, GRM Series"
				(at 20.32 -33.02 0)
				(effects
					(font
						(size 1.27 1.27)
					)
					(justify left bottom)
					(hide yes)
				)
			)
			(property "MPN" "GRM31CR60J227ME11L"
				(at 20.32 -17.78 0)
				(effects
					(font
						(size 1.27 1.27)
						(thickness 0.15)
					)
					(justify left bottom)
					(hide yes)
				)
			)
			(property "Manufacturer" "Murata"
				(at 20.32 -20.32 0)
				(effects
					(font
						(size 1.27 1.27)
						(thickness 0.15)
					)
					(justify left bottom)
					(hide yes)
				)
			)
			(property "License" "Apache-2.0"
				(at 20.32 -22.86 0)
				(effects
					(font
						(size 1.27 1.27)
						(thickness 0.15)
					)
					(justify left bottom)
					(hide yes)
				)
			)
			(property "Author" "Antmicro"
				(at 20.32 -25.4 0)
				(effects
					(font
						(size 1.27 1.27)
						(thickness 0.15)
					)
					(justify left bottom)
					(hide yes)
				)
			)
			(property "Val" "220u"
				(at 20.32 -7.62 0)
				(effects
					(font
						(size 1.27 1.27)
						(thickness 0.15)
					)
					(justify left bottom)
				)
			)
			(property "Voltage" ""
				(at 20.32 -27.94 0)
				(effects
					(font
						(size 1.27 1.27)
					)
					(justify left bottom)
					(hide yes)
				)
			)
			(property "Dielectric" ""
				(at 20.32 -30.48 0)
				(effects
					(font
						(size 1.27 1.27)
					)
					(justify left bottom)
					(hide yes)
				)
			)
			(property "Public" "False"
				(at 20.32 -33.02 0)
				(effects
					(font
						(size 1.27 1.27)
					)
					(justify left bottom)
					(hide yes)
				)
			)
			(property "ki_keywords" "1206, SMT, CAPACITOR, PASSIVE, CERAMIC, MLCC"
				(at 0 0 0)
				(effects
					(font
						(size 1.27 1.27)
					)
					(hide yes)
				)
			)
			(symbol "C_220u_1206_6V3_0_1"
				(polyline
					(pts
						(xy 2.032 -1.524) (xy 2.032 1.524)
					)
					(stroke
						(width 0.3048)
						(type default)
					)
					(fill
						(type none)
					)
				)
				(polyline
					(pts
						(xy 3.048 -1.524) (xy 3.048 1.524)
					)
					(stroke
						(width 0.3302)
						(type default)
					)
					(fill
						(type none)
					)
				)
			)
			(symbol "C_220u_1206_6V3_1_1"
				(pin passive line
					(at 0 0 0)
					(length 2.032)
					(name "~"
						(effects
							(font
								(size 1.27 1.27)
							)
						)
					)
					(number "1"
						(effects
							(font
								(size 1.27 1.27)
							)
						)
					)
				)
				(pin passive line
					(at 5.08 0 180)
					(length 2.032)
					(name "~"
						(effects
							(font
								(size 1.27 1.27)
							)
						)
					)
					(number "2"
						(effects
							(font
								(size 1.27 1.27)
							)
						)
					)
				)
			)
		)
	(symbol "antmicroCapacitorspol:C_Pol_470u_6.3V_Vishay-TR3-D"
			(pin_numbers
				(hide yes)
			)
			(pin_names
				(hide yes)
			)
			(exclude_from_sim no)
			(in_bom yes)
			(on_board yes)
			(property "Reference" "C"
				(at 13.97 0 0)
				(effects
					(font
						(size 1.27 1.27)
						(thickness 0.15)
					)
					(justify left bottom)
				)
			)
			(property "Value" "C_Pol_470u_6.3V_Vishay-TR3-D"
				(at 13.97 -2.54 0)
				(effects
					(font
						(size 1.27 1.27)
						(thickness 0.15)
					)
					(justify left bottom)
					(hide yes)
				)
			)
			(property "Footprint" "antmicro-footprints:C_Pol_EIA-D"
				(at 13.97 -7.62 0)
				(effects
					(font
						(size 1.27 1.27)
						(thickness 0.15)
					)
					(justify left bottom)
					(hide yes)
				)
			)
			(property "Datasheet" "https://www.vishay.com/docs/40080/tr3.pdf"
				(at 13.97 -10.16 0)
				(effects
					(font
						(size 1.27 1.27)
						(thickness 0.15)
					)
					(justify left bottom)
					(hide yes)
				)
			)
			(property "Description" "470 µF Molded Tantalum Capacitors 6.3 V 2917 (7343 Metric) 200mOhm"
				(at 13.97 -25.4 0)
				(effects
					(font
						(size 1.27 1.27)
					)
					(justify left bottom)
					(hide yes)
				)
			)
			(property "Val" "470u"
				(at 13.97 -5.08 0)
				(effects
					(font
						(size 1.27 1.27)
						(thickness 0.15)
					)
					(justify left bottom)
				)
			)
			(property "MPN" "TR3D477M6R3C0200"
				(at 13.97 -12.7 0)
				(effects
					(font
						(size 1.27 1.27)
						(thickness 0.15)
					)
					(justify left bottom)
					(hide yes)
				)
			)
			(property "Manufacturer" "Vishay"
				(at 13.97 -15.24 0)
				(effects
					(font
						(size 1.27 1.27)
						(thickness 0.15)
					)
					(justify left bottom)
					(hide yes)
				)
			)
			(property "License" "Apache-2.0"
				(at 13.97 -17.78 0)
				(effects
					(font
						(size 1.27 1.27)
						(thickness 0.15)
					)
					(justify left bottom)
					(hide yes)
				)
			)
			(property "Author" "Antmicro"
				(at 13.97 -20.32 0)
				(effects
					(font
						(size 1.27 1.27)
						(thickness 0.15)
					)
					(justify left bottom)
					(hide yes)
				)
			)
			(property "Voltage" "6.3V"
				(at 13.97 -22.86 0)
				(effects
					(font
						(size 1.27 1.27)
					)
					(justify left bottom)
					(hide yes)
				)
			)
			(property "Dielectric" "template_dielectric"
				(at 13.97 -25.4 0)
				(effects
					(font
						(size 1.27 1.27)
					)
					(justify left bottom)
					(hide yes)
				)
			)
			(property "ki_keywords" "SMT, CAPACITOR, PASSIVE, TANTALUM"
				(at 0 0 0)
				(effects
					(font
						(size 1.27 1.27)
					)
					(hide yes)
				)
			)
			(symbol "C_Pol_470u_6.3V_Vishay-TR3-D_0_1"
				(polyline
					(pts
						(xy 0.9652 1.27) (xy 0.9652 1.778)
					)
					(stroke
						(width 0)
						(type default)
					)
					(fill
						(type none)
					)
				)
				(polyline
					(pts
						(xy 1.2192 1.524) (xy 0.7112 1.524)
					)
					(stroke
						(width 0)
						(type default)
					)
					(fill
						(type none)
					)
				)
				(rectangle
					(start 1.905 -1.524)
					(end 2.286 1.524)
					(stroke
						(width 0)
						(type default)
					)
					(fill
						(type none)
					)
				)
				(rectangle
					(start 2.921 -1.524)
					(end 3.302 1.524)
					(stroke
						(width 0)
						(type default)
					)
					(fill
						(type outline)
					)
				)
			)
			(symbol "C_Pol_470u_6.3V_Vishay-TR3-D_1_1"
				(pin passive line
					(at 0 0 0)
					(length 1.8542)
					(name "~"
						(effects
							(font
								(size 1.27 1.27)
							)
						)
					)
					(number "1"
						(effects
							(font
								(size 1.27 1.27)
							)
						)
					)
				)
				(pin passive line
					(at 5.08 0 180)
					(length 1.8542)
					(name "~"
						(effects
							(font
								(size 1.27 1.27)
							)
						)
					)
					(number "2"
						(effects
							(font
								(size 1.27 1.27)
							)
						)
					)
				)
			)
		)
	(symbol "antmicroDCDCConverters:TPS566231P"
			(exclude_from_sim no)
			(in_bom yes)
			(on_board yes)
			(property "Reference" "U"
				(at 33.02 -2.54 0)
				(effects
					(font
						(size 1.27 1.27)
						(thickness 0.15)
					)
					(justify left bottom)
				)
			)
			(property "Value" "TPS566231P"
				(at 33.02 -5.08 0)
				(effects
					(font
						(size 1.27 1.27)
						(thickness 0.15)
					)
					(justify left bottom)
					(hide yes)
				)
			)
			(property "Footprint" "antmicro-footprints:VQFN-HR-9_2x1.5mm"
				(at 33.02 -7.62 0)
				(effects
					(font
						(size 1.27 1.27)
						(thickness 0.15)
					)
					(justify left bottom)
					(hide yes)
				)
			)
			(property "Datasheet" "https://www.ti.com/lit/ds/symlink/tps566231.pdf"
				(at 33.02 -10.16 0)
				(effects
					(font
						(size 1.27 1.27)
						(thickness 0.15)
					)
					(justify left bottom)
					(hide yes)
				)
			)
			(property "Description" "Switching Voltage Regulators 3-V to 18-V, 6-A synchronous buck converter"
				(at 33.02 -22.86 0)
				(effects
					(font
						(size 1.27 1.27)
					)
					(justify left bottom)
					(hide yes)
				)
			)
			(property "Manufacturer" "Texas Instruments"
				(at 33.02 -12.7 0)
				(effects
					(font
						(size 1.27 1.27)
						(thickness 0.15)
					)
					(justify left bottom)
					(hide yes)
				)
			)
			(property "MPN" "TPS566231PRQFR"
				(at 33.02 -15.24 0)
				(effects
					(font
						(size 1.27 1.27)
						(thickness 0.15)
					)
					(justify left bottom)
				)
			)
			(property "Author" "Antmicro"
				(at 33.02 -17.78 0)
				(effects
					(font
						(size 1.27 1.27)
						(thickness 0.15)
					)
					(justify left bottom)
					(hide yes)
				)
			)
			(property "License" "Apache-2.0"
				(at 33.02 -20.32 0)
				(effects
					(font
						(size 1.27 1.27)
						(thickness 0.15)
					)
					(justify left bottom)
					(hide yes)
				)
			)
			(property "ki_keywords" "SMT, PMIC, IC, SWITCHING, VOLTAGE, REGULATOR, DC-DC"
				(at 0 0 0)
				(effects
					(font
						(size 1.27 1.27)
					)
					(hide yes)
				)
			)
			(symbol "TPS566231P_1_1"
				(rectangle
					(start 2.54 2.54)
					(end 15.24 -17.78)
					(stroke
						(width 0.254)
						(type default)
					)
					(fill
						(type background)
					)
				)
				(pin power_in line
					(at 0 0 0)
					(length 2.54)
					(name "V_{IN}"
						(effects
							(font
								(size 1.27 1.27)
							)
						)
					)
					(number "5"
						(effects
							(font
								(size 1.27 1.27)
							)
						)
					)
				)
				(pin passive line
					(at 0 0 0)
					(length 2.54)
					(hide yes)
					(name "V_{IN}"
						(effects
							(font
								(size 1.27 1.27)
							)
						)
					)
					(number "6"
						(effects
							(font
								(size 1.27 1.27)
							)
						)
					)
				)
				(pin passive line
					(at 0 -2.54 0)
					(length 2.54)
					(name "V_{CC}"
						(effects
							(font
								(size 1.27 1.27)
							)
						)
					)
					(number "1"
						(effects
							(font
								(size 1.27 1.27)
							)
						)
					)
				)
				(pin input line
					(at 0 -10.16 0)
					(length 2.54)
					(name "EN"
						(effects
							(font
								(size 1.27 1.27)
							)
						)
					)
					(number "3"
						(effects
							(font
								(size 1.27 1.27)
							)
						)
					)
				)
				(pin passive line
					(at 0 -15.24 0)
					(length 2.54)
					(name "PG"
						(effects
							(font
								(size 1.27 1.27)
							)
						)
					)
					(number "9"
						(effects
							(font
								(size 1.27 1.27)
							)
						)
					)
				)
				(pin power_out line
					(at 17.78 0 180)
					(length 2.54)
					(name "SW"
						(effects
							(font
								(size 1.27 1.27)
							)
						)
					)
					(number "8"
						(effects
							(font
								(size 1.27 1.27)
							)
						)
					)
				)
				(pin passive line
					(at 17.78 -5.08 180)
					(length 2.54)
					(name "BST"
						(effects
							(font
								(size 1.27 1.27)
							)
						)
					)
					(number "7"
						(effects
							(font
								(size 1.27 1.27)
							)
						)
					)
				)
				(pin input line
					(at 17.78 -10.16 180)
					(length 2.54)
					(name "FB"
						(effects
							(font
								(size 1.27 1.27)
							)
						)
					)
					(number "2"
						(effects
							(font
								(size 1.27 1.27)
							)
						)
					)
				)
				(pin power_in line
					(at 17.78 -15.24 180)
					(length 2.54)
					(name "PGND"
						(effects
							(font
								(size 1.27 1.27)
							)
						)
					)
					(number "4"
						(effects
							(font
								(size 1.27 1.27)
							)
						)
					)
				)
			)
		)
	(symbol "antmicroDiodesRectifiersSingle:RB521S30T1G"
			(pin_numbers
				(hide yes)
			)
			(pin_names
				(hide yes)
			)
			(exclude_from_sim no)
			(in_bom yes)
			(on_board yes)
			(property "Reference" "D"
				(at 22.86 -5.08 0)
				(effects
					(font
						(size 1.27 1.27)
						(thickness 0.15)
					)
					(justify left bottom)
				)
			)
			(property "Value" "RB521S30T1G"
				(at 22.86 -15.24 0)
				(effects
					(font
						(size 1.27 1.27)
						(thickness 0.15)
					)
					(justify left bottom)
					(hide yes)
				)
			)
			(property "Footprint" "antmicro-footprints:SOD-523"
				(at 22.86 -10.16 0)
				(effects
					(font
						(size 1.27 1.27)
						(thickness 0.15)
					)
					(justify left bottom)
					(hide yes)
				)
			)
			(property "Datasheet" "https://www.onsemi.com/pdf/datasheet/rb521s30t1-d.pdf"
				(at 22.86 -12.7 0)
				(effects
					(font
						(size 1.27 1.27)
						(thickness 0.15)
					)
					(justify left bottom)
					(hide yes)
				)
			)
			(property "Description" "Small Signal Schottky Diode, Single, 30 V, 200 mA, 500 mV, 1 A, 125 °C"
				(at 22.86 -25.4 0)
				(effects
					(font
						(size 1.27 1.27)
					)
					(justify left bottom)
					(hide yes)
				)
			)
			(property "MPN" "RB521S30T1G"
				(at 22.86 -7.62 0)
				(effects
					(font
						(size 1.27 1.27)
						(thickness 0.15)
					)
					(justify left bottom)
				)
			)
			(property "Manufacturer" "ON Semiconductor"
				(at 22.86 -17.78 0)
				(effects
					(font
						(size 1.27 1.27)
						(thickness 0.15)
					)
					(justify left bottom)
					(hide yes)
				)
			)
			(property "Author" "Antmicro"
				(at 22.86 -20.32 0)
				(effects
					(font
						(size 1.27 1.27)
						(thickness 0.15)
					)
					(justify left bottom)
					(hide yes)
				)
			)
			(property "License" "Apache-2.0"
				(at 22.86 -22.86 0)
				(effects
					(font
						(size 1.27 1.27)
						(thickness 0.15)
					)
					(justify left bottom)
					(hide yes)
				)
			)
			(property "ki_keywords" "SMT, SEMICONDUCTOR, DIODE, SCHOTTKY"
				(at 0 0 0)
				(effects
					(font
						(size 1.27 1.27)
					)
					(hide yes)
				)
			)
			(symbol "RB521S30T1G_0_1"
				(polyline
					(pts
						(xy 1.905 0) (xy 0.635 0)
					)
					(stroke
						(width 0)
						(type default)
					)
					(fill
						(type none)
					)
				)
				(polyline
					(pts
						(xy 4.445 0) (xy 3.175 0)
					)
					(stroke
						(width 0)
						(type default)
					)
					(fill
						(type none)
					)
				)
			)
			(symbol "RB521S30T1G_1_1"
				(polyline
					(pts
						(xy 1.778 1.016) (xy 1.778 -1.016)
					)
					(stroke
						(width 0.254)
						(type default)
					)
					(fill
						(type none)
					)
				)
				(polyline
					(pts
						(xy 1.778 1.016) (xy 1.397 1.016) (xy 1.397 0.762)
					)
					(stroke
						(width 0.254)
						(type default)
					)
					(fill
						(type none)
					)
				)
				(polyline
					(pts
						(xy 1.778 -1.016) (xy 2.159 -1.016) (xy 2.159 -0.762)
					)
					(stroke
						(width 0.254)
						(type default)
					)
					(fill
						(type none)
					)
				)
				(polyline
					(pts
						(xy 3.302 1.016) (xy 3.302 -1.016) (xy 1.778 0) (xy 3.302 1.016)
					)
					(stroke
						(width 0.254)
						(type default)
					)
					(fill
						(type outline)
					)
				)
				(pin passive line
					(at 0 0 0)
					(length 0.635)
					(name "C"
						(effects
							(font
								(size 1.27 1.27)
							)
						)
					)
					(number "1"
						(effects
							(font
								(size 1.27 1.27)
							)
						)
					)
				)
				(pin passive line
					(at 5.08 0 180)
					(length 0.635)
					(name "A"
						(effects
							(font
								(size 1.27 1.27)
							)
						)
					)
					(number "2"
						(effects
							(font
								(size 1.27 1.27)
							)
						)
					)
				)
			)
		)
	(symbol "antmicroFerriteBeadsandChips:FB_330Z_1.5A_Murata-BLM21PG_0805"
			(pin_numbers
				(hide yes)
			)
			(pin_names
				(hide yes)
			)
			(exclude_from_sim no)
			(in_bom yes)
			(on_board yes)
			(property "Reference" "FB"
				(at 13.97 0 0)
				(effects
					(font
						(size 1.27 1.27)
						(thickness 0.15)
					)
					(justify left bottom)
				)
			)
			(property "Value" "FB_330Z_1.5A_Murata-BLM21PG_0805"
				(at 13.97 -2.54 0)
				(effects
					(font
						(size 1.27 1.27)
						(thickness 0.15)
					)
					(justify left bottom)
					(hide yes)
				)
			)
			(property "Footprint" "antmicro-footprints:FB_0805_2012Metric"
				(at 13.97 -7.62 0)
				(effects
					(font
						(size 1.27 1.27)
						(thickness 0.15)
					)
					(justify left bottom)
					(hide yes)
				)
			)
			(property "Datasheet" "https://www.murata.com/products/productdata/8796738977822/ENFA0005.pdf?1653276712000"
				(at 13.97 -10.16 0)
				(effects
					(font
						(size 1.27 1.27)
						(thickness 0.15)
					)
					(justify left bottom)
					(hide yes)
				)
			)
			(property "Description" "Ferrite Bead, 0805 [2012 Metric], 330 ohm, 1.5 A, BLM21P, 0.07 ohm, ± 25%, DC power line"
				(at 13.97 -22.86 0)
				(effects
					(font
						(size 1.27 1.27)
					)
					(justify left bottom)
					(hide yes)
				)
			)
			(property "Val" "330Z/1.5A"
				(at 13.97 -5.08 0)
				(effects
					(font
						(size 1.27 1.27)
					)
					(justify left bottom)
				)
			)
			(property "MPN" "BLM21PG331SN1D"
				(at 13.97 -12.7 0)
				(effects
					(font
						(size 1.27 1.27)
						(thickness 0.15)
					)
					(justify left bottom)
					(hide yes)
				)
			)
			(property "Manufacturer" "Murata"
				(at 13.97 -15.24 0)
				(effects
					(font
						(size 1.27 1.27)
						(thickness 0.15)
					)
					(justify left bottom)
					(hide yes)
				)
			)
			(property "Current" ""
				(at 20.32 -22.86 0)
				(effects
					(font
						(size 1.27 1.27)
						(thickness 0.15)
					)
					(justify left bottom)
					(hide yes)
				)
			)
			(property "Author" "Antmicro"
				(at 13.97 -17.78 0)
				(effects
					(font
						(size 1.27 1.27)
						(thickness 0.15)
					)
					(justify left bottom)
					(hide yes)
				)
			)
			(property "License" "Apache-2.0"
				(at 13.97 -20.32 0)
				(effects
					(font
						(size 1.27 1.27)
						(thickness 0.15)
					)
					(justify left bottom)
					(hide yes)
				)
			)
			(property "ki_keywords" "0805, SMT, FERRITE BEAD, PASSIVE"
				(at 0 0 0)
				(effects
					(font
						(size 1.27 1.27)
					)
					(hide yes)
				)
			)
			(symbol "FB_330Z_1.5A_Murata-BLM21PG_0805_0_1"
				(polyline
					(pts
						(xy 1.651 0) (xy 1.2446 0)
					)
					(stroke
						(width 0)
						(type default)
					)
					(fill
						(type none)
					)
				)
				(polyline
					(pts
						(xy 2.2606 -1.8288) (xy 1.0414 -1.1176) (xy 2.7432 1.8288) (xy 3.9624 1.1176) (xy 2.2606 -1.8288)
					)
					(stroke
						(width 0)
						(type default)
					)
					(fill
						(type none)
					)
				)
				(polyline
					(pts
						(xy 3.81 0) (xy 3.3274 0)
					)
					(stroke
						(width 0)
						(type default)
					)
					(fill
						(type none)
					)
				)
			)
			(symbol "FB_330Z_1.5A_Murata-BLM21PG_0805_1_1"
				(pin passive line
					(at 0 0 0)
					(length 1.27)
					(name "~"
						(effects
							(font
								(size 1.27 1.27)
							)
						)
					)
					(number "1"
						(effects
							(font
								(size 1.27 1.27)
							)
						)
					)
				)
				(pin passive line
					(at 5.08 0 180)
					(length 1.27)
					(name "~"
						(effects
							(font
								(size 1.27 1.27)
							)
						)
					)
					(number "2"
						(effects
							(font
								(size 1.27 1.27)
							)
						)
					)
				)
			)
		)
	(symbol "antmicroFerriteBeadsandChips:FB_33Z_3A_Murata-BLM18PG_0603"
			(pin_numbers
				(hide yes)
			)
			(pin_names
				(hide yes)
			)
			(exclude_from_sim no)
			(in_bom yes)
			(on_board yes)
			(property "Reference" "FB"
				(at 13.97 0 0)
				(effects
					(font
						(size 1.27 1.27)
						(thickness 0.15)
					)
					(justify left bottom)
				)
			)
			(property "Value" "FB_33Z_3A_Murata-BLM18PG_0603"
				(at 13.97 -2.54 0)
				(effects
					(font
						(size 1.27 1.27)
						(thickness 0.15)
					)
					(justify left bottom)
					(hide yes)
				)
			)
			(property "Footprint" "antmicro-footprints:FB_0603_1608Metric"
				(at 13.97 -7.62 0)
				(effects
					(font
						(size 1.27 1.27)
						(thickness 0.15)
					)
					(justify left bottom)
					(hide yes)
				)
			)
			(property "Datasheet" "https://www.murata.com/products/productdata/8796737273886/QNFA9101.pdf?1649080818000"
				(at 13.97 -10.16 0)
				(effects
					(font
						(size 1.27 1.27)
						(thickness 0.15)
					)
					(justify left bottom)
					(hide yes)
				)
			)
			(property "Description" "Ferrite Bead, 0603 [1608 Metric], 33 ohm, 3 A, BLM18PG, 0.025 ohm, ± 25%, DC power line"
				(at 13.97 -22.86 0)
				(effects
					(font
						(size 1.27 1.27)
					)
					(justify left bottom)
					(hide yes)
				)
			)
			(property "Val" "33Z/3A"
				(at 13.97 -5.08 0)
				(effects
					(font
						(size 1.27 1.27)
					)
					(justify left bottom)
				)
			)
			(property "MPN" "BLM18PG330SH1D"
				(at 13.97 -12.7 0)
				(effects
					(font
						(size 1.27 1.27)
						(thickness 0.15)
					)
					(justify left bottom)
					(hide yes)
				)
			)
			(property "Manufacturer" "Murata"
				(at 13.97 -15.24 0)
				(effects
					(font
						(size 1.27 1.27)
						(thickness 0.15)
					)
					(justify left bottom)
					(hide yes)
				)
			)
			(property "Current" ""
				(at 20.32 -22.86 0)
				(effects
					(font
						(size 1.27 1.27)
						(thickness 0.15)
					)
					(justify left bottom)
					(hide yes)
				)
			)
			(property "Author" "Antmicro"
				(at 13.97 -17.78 0)
				(effects
					(font
						(size 1.27 1.27)
						(thickness 0.15)
					)
					(justify left bottom)
					(hide yes)
				)
			)
			(property "License" "Apache-2.0"
				(at 13.97 -20.32 0)
				(effects
					(font
						(size 1.27 1.27)
						(thickness 0.15)
					)
					(justify left bottom)
					(hide yes)
				)
			)
			(property "ki_keywords" "0603, SMT, FERRITE BEAD, PASSIVE"
				(at 0 0 0)
				(effects
					(font
						(size 1.27 1.27)
					)
					(hide yes)
				)
			)
			(symbol "FB_33Z_3A_Murata-BLM18PG_0603_0_1"
				(polyline
					(pts
						(xy 1.651 0) (xy 1.2446 0)
					)
					(stroke
						(width 0)
						(type default)
					)
					(fill
						(type none)
					)
				)
				(polyline
					(pts
						(xy 2.2606 -1.8288) (xy 1.0414 -1.1176) (xy 2.7432 1.8288) (xy 3.9624 1.1176) (xy 2.2606 -1.8288)
					)
					(stroke
						(width 0)
						(type default)
					)
					(fill
						(type none)
					)
				)
				(polyline
					(pts
						(xy 3.81 0) (xy 3.3274 0)
					)
					(stroke
						(width 0)
						(type default)
					)
					(fill
						(type none)
					)
				)
			)
			(symbol "FB_33Z_3A_Murata-BLM18PG_0603_1_1"
				(pin passive line
					(at 0 0 0)
					(length 1.27)
					(name "~"
						(effects
							(font
								(size 1.27 1.27)
							)
						)
					)
					(number "1"
						(effects
							(font
								(size 1.27 1.27)
							)
						)
					)
				)
				(pin passive line
					(at 5.08 0 180)
					(length 1.27)
					(name "~"
						(effects
							(font
								(size 1.27 1.27)
							)
						)
					)
					(number "2"
						(effects
							(font
								(size 1.27 1.27)
							)
						)
					)
				)
			)
		)
	(symbol "antmicroFerriteBeadsandChips:FB_470Z_1A_Murata-BLM18PG_0603"
			(pin_numbers
				(hide yes)
			)
			(pin_names
				(hide yes)
			)
			(exclude_from_sim no)
			(in_bom yes)
			(on_board yes)
			(property "Reference" "FB"
				(at 13.97 0 0)
				(effects
					(font
						(size 1.27 1.27)
						(thickness 0.15)
					)
					(justify left bottom)
				)
			)
			(property "Value" "FB_470Z_1A_Murata-BLM18PG_0603"
				(at 13.97 -2.54 0)
				(effects
					(font
						(size 1.27 1.27)
						(thickness 0.15)
					)
					(justify left bottom)
					(hide yes)
				)
			)
			(property "Footprint" "antmicro-footprints:FB_0603_1608Metric"
				(at 13.97 -7.62 0)
				(effects
					(font
						(size 1.27 1.27)
						(thickness 0.15)
					)
					(justify left bottom)
					(hide yes)
				)
			)
			(property "Datasheet" "https://www.murata.com/en-us/products/productdata/8796738650142/ENFA0003.pdf"
				(at 13.97 -10.16 0)
				(effects
					(font
						(size 1.27 1.27)
						(thickness 0.15)
					)
					(justify left bottom)
					(hide yes)
				)
			)
			(property "Description" "Ferrite Bead, 0603 [1608 Metric], 470 ohm, 1 A, BLM18P, 0.2 ohm, ± 25%, DC power line"
				(at 13.97 -22.86 0)
				(effects
					(font
						(size 1.27 1.27)
					)
					(justify left bottom)
					(hide yes)
				)
			)
			(property "Val" "470Z/1A"
				(at 13.97 -5.08 0)
				(effects
					(font
						(size 1.27 1.27)
					)
					(justify left bottom)
				)
			)
			(property "MPN" "BLM18PG471SN1D"
				(at 13.97 -12.7 0)
				(effects
					(font
						(size 1.27 1.27)
						(thickness 0.15)
					)
					(justify left bottom)
					(hide yes)
				)
			)
			(property "Manufacturer" "Murata"
				(at 13.97 -15.24 0)
				(effects
					(font
						(size 1.27 1.27)
						(thickness 0.15)
					)
					(justify left bottom)
					(hide yes)
				)
			)
			(property "Current" ""
				(at 20.32 -22.86 0)
				(effects
					(font
						(size 1.27 1.27)
						(thickness 0.15)
					)
					(justify left bottom)
					(hide yes)
				)
			)
			(property "Author" "Antmicro"
				(at 13.97 -17.78 0)
				(effects
					(font
						(size 1.27 1.27)
						(thickness 0.15)
					)
					(justify left bottom)
					(hide yes)
				)
			)
			(property "License" "Apache-2.0"
				(at 13.97 -20.32 0)
				(effects
					(font
						(size 1.27 1.27)
						(thickness 0.15)
					)
					(justify left bottom)
					(hide yes)
				)
			)
			(property "ki_keywords" "0603, SMT, FERRITE BEAD, PASSIVE"
				(at 0 0 0)
				(effects
					(font
						(size 1.27 1.27)
					)
					(hide yes)
				)
			)
			(symbol "FB_470Z_1A_Murata-BLM18PG_0603_0_1"
				(polyline
					(pts
						(xy 1.651 0) (xy 1.2446 0)
					)
					(stroke
						(width 0)
						(type default)
					)
					(fill
						(type none)
					)
				)
				(polyline
					(pts
						(xy 2.2606 -1.8288) (xy 1.0414 -1.1176) (xy 2.7432 1.8288) (xy 3.9624 1.1176) (xy 2.2606 -1.8288)
					)
					(stroke
						(width 0)
						(type default)
					)
					(fill
						(type none)
					)
				)
				(polyline
					(pts
						(xy 3.81 0) (xy 3.3274 0)
					)
					(stroke
						(width 0)
						(type default)
					)
					(fill
						(type none)
					)
				)
			)
			(symbol "FB_470Z_1A_Murata-BLM18PG_0603_1_1"
				(pin passive line
					(at 0 0 0)
					(length 1.27)
					(name "~"
						(effects
							(font
								(size 1.27 1.27)
							)
						)
					)
					(number "1"
						(effects
							(font
								(size 1.27 1.27)
							)
						)
					)
				)
				(pin passive line
					(at 5.08 0 180)
					(length 1.27)
					(name "~"
						(effects
							(font
								(size 1.27 1.27)
							)
						)
					)
					(number "2"
						(effects
							(font
								(size 1.27 1.27)
							)
						)
					)
				)
			)
		)
	(symbol "antmicroFixedInductors:L_1u_10A_Bourns-SRP4021HMT"
			(pin_numbers
				(hide yes)
			)
			(pin_names
				(hide yes)
			)
			(exclude_from_sim no)
			(in_bom yes)
			(on_board yes)
			(property "Reference" "L"
				(at 15.24 -5.08 0)
				(effects
					(font
						(size 1.27 1.27)
						(thickness 0.15)
					)
					(justify left bottom)
				)
			)
			(property "Value" "L_1u_10A_Bourns-SRP4021HMT"
				(at 15.24 -10.16 0)
				(effects
					(font
						(size 1.27 1.27)
						(thickness 0.15)
					)
					(justify left bottom)
					(hide yes)
				)
			)
			(property "Footprint" "antmicro-footprints:L_Bourns-SRP4021HMT"
				(at 15.24 -12.7 0)
				(effects
					(font
						(size 1.27 1.27)
						(thickness 0.15)
					)
					(justify left bottom)
					(hide yes)
				)
			)
			(property "Datasheet" "https://www.mouser.com/datasheet/2/54/Bourns_04_01_2025_SRP4021HMT_Datasheet-3580094.pdf"
				(at 15.24 -15.24 0)
				(effects
					(font
						(size 1.27 1.27)
						(thickness 0.15)
					)
					(justify left bottom)
					(hide yes)
				)
			)
			(property "Description" "Power Inductors - SMD Ind,4.1x4.2x1.9mm,1uH+/-20%,10A, Shielded"
				(at 15.24 -38.1 0)
				(effects
					(font
						(size 1.27 1.27)
						(thickness 0.15)
					)
					(justify left bottom)
					(hide yes)
				)
			)
			(property "Val" "1u/10A"
				(at 15.24 -7.62 0)
				(effects
					(font
						(size 1.27 1.27)
						(thickness 0.15)
					)
					(justify left bottom)
				)
			)
			(property "Manufacturer" "Bourns"
				(at 15.24 -20.32 0)
				(effects
					(font
						(size 1.27 1.27)
						(thickness 0.15)
					)
					(justify left bottom)
					(hide yes)
				)
			)
			(property "MPN" "SRP4021HMT-1R0M"
				(at 15.24 -22.86 0)
				(effects
					(font
						(size 1.27 1.27)
						(thickness 0.15)
					)
					(justify left bottom)
					(hide yes)
				)
			)
			(property "ISat" ""
				(at 13.97 -16.51 0)
				(effects
					(font
						(size 1.27 1.27)
					)
					(justify left)
					(hide yes)
				)
			)
			(property "Isat" "8A"
				(at 15.24 -25.4 0)
				(effects
					(font
						(size 1.27 1.27)
						(thickness 0.15)
					)
					(justify left bottom)
					(hide yes)
				)
			)
			(property "IMax" ""
				(at 13.97 -20.32 0)
				(effects
					(font
						(size 1.27 1.27)
						(thickness 0.15)
					)
					(justify left bottom)
					(hide yes)
				)
			)
			(property "Imax" "10A"
				(at 15.24 -27.94 0)
				(effects
					(font
						(size 1.27 1.27)
						(thickness 0.15)
					)
					(justify left bottom)
					(hide yes)
				)
			)
			(property "Size" "4.2x4.1"
				(at 15.24 -30.48 0)
				(effects
					(font
						(size 1.27 1.27)
						(thickness 0.15)
					)
					(justify left bottom)
					(hide yes)
				)
			)
			(property "Author" "Antmicro"
				(at 15.24 -33.02 0)
				(effects
					(font
						(size 1.27 1.27)
						(thickness 0.15)
					)
					(justify left bottom)
					(hide yes)
				)
			)
			(property "License" "Apache-2.0"
				(at 15.24 -35.56 0)
				(effects
					(font
						(size 1.27 1.27)
						(thickness 0.15)
					)
					(justify left bottom)
					(hide yes)
				)
			)
			(property "ki_keywords" "SMT, INDUCTOR, PASSIVE"
				(at 0 0 0)
				(effects
					(font
						(size 1.27 1.27)
					)
					(hide yes)
				)
			)
			(symbol "L_1u_10A_Bourns-SRP4021HMT_0_1"
				(arc
					(start 0.508 0)
					(mid 1.016 0.5058)
					(end 1.524 0)
					(stroke
						(width 0)
						(type default)
					)
					(fill
						(type none)
					)
				)
				(arc
					(start 1.524 0)
					(mid 2.032 0.5058)
					(end 2.54 0)
					(stroke
						(width 0)
						(type default)
					)
					(fill
						(type none)
					)
				)
				(arc
					(start 2.54 0)
					(mid 3.048 0.5058)
					(end 3.556 0)
					(stroke
						(width 0)
						(type default)
					)
					(fill
						(type none)
					)
				)
				(arc
					(start 3.556 0)
					(mid 4.064 0.5058)
					(end 4.572 0)
					(stroke
						(width 0)
						(type default)
					)
					(fill
						(type none)
					)
				)
			)
			(symbol "L_1u_10A_Bourns-SRP4021HMT_1_1"
				(pin passive line
					(at 0 0 0)
					(length 0.508)
					(name "~"
						(effects
							(font
								(size 1.27 1.27)
							)
						)
					)
					(number "1"
						(effects
							(font
								(size 1.27 1.27)
							)
						)
					)
				)
				(pin passive line
					(at 5.08 0 180)
					(length 0.508)
					(name "~"
						(effects
							(font
								(size 1.27 1.27)
							)
						)
					)
					(number "2"
						(effects
							(font
								(size 1.27 1.27)
							)
						)
					)
				)
			)
		)
	(symbol "antmicroFixedInductors:L_2n4_0.85A_0402"
			(pin_numbers
				(hide yes)
			)
			(pin_names
				(hide yes)
			)
			(exclude_from_sim no)
			(in_bom yes)
			(on_board yes)
			(property "Reference" "L"
				(at 13.97 0 0)
				(effects
					(font
						(size 1.27 1.27)
						(thickness 0.15)
					)
					(justify left bottom)
				)
			)
			(property "Value" "L_2n4_0.85A_0402"
				(at 13.97 -2.54 0)
				(effects
					(font
						(size 1.27 1.27)
						(thickness 0.15)
					)
					(justify left bottom)
					(hide yes)
				)
			)
			(property "Footprint" "antmicro-footprints:L_0402_1005Metric"
				(at 13.97 -7.62 0)
				(effects
					(font
						(size 1.27 1.27)
						(thickness 0.15)
					)
					(justify left bottom)
					(hide yes)
				)
			)
			(property "Datasheet" "https://www.murata.com/products/productdetail?partno=LQW15AN2N4B00%23"
				(at 13.97 -10.16 0)
				(effects
					(font
						(size 1.27 1.27)
						(thickness 0.15)
					)
					(justify left bottom)
					(hide yes)
				)
			)
			(property "Description" "Wirewound Inductor, 2.4 nH, 0.05 ohm, 15 GHz, 850 mA, 0402 [1005 Metric], LQW15AN"
				(at 13.97 -30.48 0)
				(effects
					(font
						(size 1.27 1.27)
					)
					(justify left bottom)
					(hide yes)
				)
			)
			(property "Val" "2n4/0.85A"
				(at 13.97 -5.08 0)
				(effects
					(font
						(size 1.27 1.27)
						(thickness 0.15)
					)
					(justify left bottom)
				)
			)
			(property "Manufacturer" "Murata"
				(at 13.97 -12.7 0)
				(effects
					(font
						(size 1.27 1.27)
						(thickness 0.15)
					)
					(justify left bottom)
					(hide yes)
				)
			)
			(property "MPN" "LQW15AN2N4B00D"
				(at 13.97 -15.24 0)
				(effects
					(font
						(size 1.27 1.27)
						(thickness 0.15)
					)
					(justify left bottom)
					(hide yes)
				)
			)
			(property "ISat" "0.85 A"
				(at 13.97 -16.51 0)
				(effects
					(font
						(size 1.27 1.27)
					)
					(justify left)
					(hide yes)
				)
			)
			(property "IMax" "0.85 A"
				(at 13.97 -20.32 0)
				(effects
					(font
						(size 1.27 1.27)
						(thickness 0.15)
					)
					(justify left bottom)
					(hide yes)
				)
			)
			(property "Size" "1.0x0.5"
				(at 13.97 -22.86 0)
				(effects
					(font
						(size 1.27 1.27)
						(thickness 0.15)
					)
					(justify left bottom)
					(hide yes)
				)
			)
			(property "Author" "Antmicro"
				(at 13.97 -25.4 0)
				(effects
					(font
						(size 1.27 1.27)
						(thickness 0.15)
					)
					(justify left bottom)
					(hide yes)
				)
			)
			(property "License" "Apache-2.0"
				(at 13.97 -27.94 0)
				(effects
					(font
						(size 1.27 1.27)
						(thickness 0.15)
					)
					(justify left bottom)
					(hide yes)
				)
			)
			(property "ki_keywords" "INDUCTOR, PASSIVE"
				(at 0 0 0)
				(effects
					(font
						(size 1.27 1.27)
					)
					(hide yes)
				)
			)
			(symbol "L_2n4_0.85A_0402_0_1"
				(arc
					(start 0.508 0)
					(mid 1.016 0.5058)
					(end 1.524 0)
					(stroke
						(width 0)
						(type default)
					)
					(fill
						(type none)
					)
				)
				(arc
					(start 1.524 0)
					(mid 2.032 0.5058)
					(end 2.54 0)
					(stroke
						(width 0)
						(type default)
					)
					(fill
						(type none)
					)
				)
				(arc
					(start 2.54 0)
					(mid 3.048 0.5058)
					(end 3.556 0)
					(stroke
						(width 0)
						(type default)
					)
					(fill
						(type none)
					)
				)
				(arc
					(start 3.556 0)
					(mid 4.064 0.5058)
					(end 4.572 0)
					(stroke
						(width 0)
						(type default)
					)
					(fill
						(type none)
					)
				)
			)
			(symbol "L_2n4_0.85A_0402_1_1"
				(pin passive line
					(at 0 0 0)
					(length 0.508)
					(name "~"
						(effects
							(font
								(size 1.27 1.27)
							)
						)
					)
					(number "1"
						(effects
							(font
								(size 1.27 1.27)
							)
						)
					)
				)
				(pin passive line
					(at 5.08 0 180)
					(length 0.508)
					(name "~"
						(effects
							(font
								(size 1.27 1.27)
							)
						)
					)
					(number "2"
						(effects
							(font
								(size 1.27 1.27)
							)
						)
					)
				)
			)
		)
	(symbol "antmicroFixedInductors:L_2u2_5.8A_WE-PMFI-35329222"
			(pin_numbers
				(hide yes)
			)
			(pin_names
				(hide yes)
			)
			(exclude_from_sim no)
			(in_bom yes)
			(on_board yes)
			(property "Reference" "L"
				(at 13.97 0 0)
				(effects
					(font
						(size 1.27 1.27)
						(thickness 0.15)
					)
					(justify left bottom)
				)
			)
			(property "Value" "L_2u2_5.8A_WE-PMFI-35329222"
				(at 13.97 -2.54 0)
				(effects
					(font
						(size 1.27 1.27)
						(thickness 0.15)
					)
					(justify left bottom)
					(hide yes)
				)
			)
			(property "Footprint" "antmicro-footprints:L_WE-PMFI-353220"
				(at 13.97 -7.62 0)
				(effects
					(font
						(size 1.27 1.27)
						(thickness 0.15)
					)
					(justify left bottom)
					(hide yes)
				)
			)
			(property "Datasheet" "https://www.we-online.com/components/products/datasheet/74479335329222.pdf"
				(at 13.97 -10.16 0)
				(effects
					(font
						(size 1.27 1.27)
						(thickness 0.15)
					)
					(justify left bottom)
					(hide yes)
				)
			)
			(property "Description" "Power Inductors - SMD WE-PMFI 2.2 uH 5.8 A 40 mOhms AEC-Q200"
				(at 13.97 -30.48 0)
				(effects
					(font
						(size 1.27 1.27)
					)
					(justify left bottom)
					(hide yes)
				)
			)
			(property "Val" "2u2/5.8A"
				(at 13.97 -5.08 0)
				(effects
					(font
						(size 1.27 1.27)
						(thickness 0.15)
					)
					(justify left bottom)
				)
			)
			(property "Manufacturer" "Würth Elektronik"
				(at 13.97 -12.7 0)
				(effects
					(font
						(size 1.27 1.27)
						(thickness 0.15)
					)
					(justify left bottom)
					(hide yes)
				)
			)
			(property "MPN" "74479335329222"
				(at 13.97 -15.24 0)
				(effects
					(font
						(size 1.27 1.27)
						(thickness 0.15)
					)
					(justify left bottom)
					(hide yes)
				)
			)
			(property "ISat" "7.8A"
				(at 13.97 -17.78 0)
				(effects
					(font
						(size 1.27 1.27)
					)
					(justify left bottom)
					(hide yes)
				)
			)
			(property "IMax" "5.8A"
				(at 13.97 -20.32 0)
				(effects
					(font
						(size 1.27 1.27)
						(thickness 0.15)
					)
					(justify left bottom)
					(hide yes)
				)
			)
			(property "Size" "3.5x3.2x2.0"
				(at 13.97 -22.86 0)
				(effects
					(font
						(size 1.27 1.27)
						(thickness 0.15)
					)
					(justify left bottom)
					(hide yes)
				)
			)
			(property "Author" "Antmicro"
				(at 13.97 -25.4 0)
				(effects
					(font
						(size 1.27 1.27)
						(thickness 0.15)
					)
					(justify left bottom)
					(hide yes)
				)
			)
			(property "License" "Apache-2.0"
				(at 13.97 -27.94 0)
				(effects
					(font
						(size 1.27 1.27)
						(thickness 0.15)
					)
					(justify left bottom)
					(hide yes)
				)
			)
			(property "ki_keywords" "SMT, INDUCTOR, PASSIVE"
				(at 0 0 0)
				(effects
					(font
						(size 1.27 1.27)
					)
					(hide yes)
				)
			)
			(symbol "L_2u2_5.8A_WE-PMFI-35329222_0_1"
				(arc
					(start 0.508 0)
					(mid 1.016 0.5058)
					(end 1.524 0)
					(stroke
						(width 0)
						(type default)
					)
					(fill
						(type none)
					)
				)
				(arc
					(start 1.524 0)
					(mid 2.032 0.5058)
					(end 2.54 0)
					(stroke
						(width 0)
						(type default)
					)
					(fill
						(type none)
					)
				)
				(arc
					(start 2.54 0)
					(mid 3.048 0.5058)
					(end 3.556 0)
					(stroke
						(width 0)
						(type default)
					)
					(fill
						(type none)
					)
				)
				(arc
					(start 3.556 0)
					(mid 4.064 0.5058)
					(end 4.572 0)
					(stroke
						(width 0)
						(type default)
					)
					(fill
						(type none)
					)
				)
			)
			(symbol "L_2u2_5.8A_WE-PMFI-35329222_1_1"
				(pin passive line
					(at 0 0 0)
					(length 0.508)
					(name "~"
						(effects
							(font
								(size 1.27 1.27)
							)
						)
					)
					(number "1"
						(effects
							(font
								(size 1.27 1.27)
							)
						)
					)
				)
				(pin passive line
					(at 5.08 0 180)
					(length 0.508)
					(name "~"
						(effects
							(font
								(size 1.27 1.27)
							)
						)
					)
					(number "2"
						(effects
							(font
								(size 1.27 1.27)
							)
						)
					)
				)
			)
		)
	(symbol "antmicroFixedInductors:L_4u7_1.55A_Bourns-SRP2512A"
			(pin_numbers
				(hide yes)
			)
			(pin_names
				(hide yes)
			)
			(exclude_from_sim no)
			(in_bom yes)
			(on_board yes)
			(property "Reference" "L"
				(at 15.24 0 0)
				(effects
					(font
						(size 1.27 1.27)
						(thickness 0.15)
					)
					(justify left bottom)
				)
			)
			(property "Value" "L_4u7_1.55A_Bourns-SRP2512A"
				(at 15.24 -5.08 0)
				(effects
					(font
						(size 1.27 1.27)
						(thickness 0.15)
					)
					(justify left bottom)
					(hide yes)
				)
			)
			(property "Footprint" "antmicro-footprints:L_Bourns-SRP2512A"
				(at 15.24 -7.62 0)
				(effects
					(font
						(size 1.27 1.27)
						(thickness 0.15)
					)
					(justify left bottom)
					(hide yes)
				)
			)
			(property "Datasheet" "https://www.bourns.com/docs/Product-Datasheets/srp2512a.pdf"
				(at 15.24 -10.16 0)
				(effects
					(font
						(size 1.27 1.27)
						(thickness 0.15)
					)
					(justify left bottom)
					(hide yes)
				)
			)
			(property "Description" "4.7 µH Shielded Drum Core, Wirewound Inductor 1.55 A 235mOhm Max 1008 (2520 Metric)"
				(at 15.24 -30.48 0)
				(effects
					(font
						(size 1.27 1.27)
					)
					(justify left bottom)
					(hide yes)
				)
			)
			(property "Val" "4u7/1.55A"
				(at 15.24 -2.54 0)
				(effects
					(font
						(size 1.27 1.27)
						(thickness 0.15)
					)
					(justify left bottom)
				)
			)
			(property "Manufacturer" "Bourns"
				(at 15.24 -12.7 0)
				(effects
					(font
						(size 1.27 1.27)
						(thickness 0.15)
					)
					(justify left bottom)
					(hide yes)
				)
			)
			(property "MPN" "SRP2512A-4R7M"
				(at 15.24 -15.24 0)
				(effects
					(font
						(size 1.27 1.27)
						(thickness 0.15)
					)
					(justify left bottom)
					(hide yes)
				)
			)
			(property "ISat" "1.9 A"
				(at 15.24 -17.78 0)
				(effects
					(font
						(size 1.27 1.27)
					)
					(justify left bottom)
					(hide yes)
				)
			)
			(property "IMax" "1.55 A"
				(at 15.24 -20.32 0)
				(effects
					(font
						(size 1.27 1.27)
					)
					(justify left bottom)
					(hide yes)
				)
			)
			(property "Size" "2.5x2.0"
				(at 15.24 -22.86 0)
				(effects
					(font
						(size 1.27 1.27)
					)
					(justify left bottom)
					(hide yes)
				)
			)
			(property "Author" "Antmicro"
				(at 15.24 -25.4 0)
				(effects
					(font
						(size 1.27 1.27)
						(thickness 0.15)
					)
					(justify left bottom)
					(hide yes)
				)
			)
			(property "License" "Apache-2.0"
				(at 15.24 -27.94 0)
				(effects
					(font
						(size 1.27 1.27)
						(thickness 0.15)
					)
					(justify left bottom)
					(hide yes)
				)
			)
			(property "ki_keywords" "INDUCTOR, PASSIVE"
				(at 0 0 0)
				(effects
					(font
						(size 1.27 1.27)
					)
					(hide yes)
				)
			)
			(symbol "L_4u7_1.55A_Bourns-SRP2512A_0_1"
				(arc
					(start 0.508 0)
					(mid 1.016 0.5058)
					(end 1.524 0)
					(stroke
						(width 0)
						(type default)
					)
					(fill
						(type none)
					)
				)
				(arc
					(start 1.524 0)
					(mid 2.032 0.5058)
					(end 2.54 0)
					(stroke
						(width 0)
						(type default)
					)
					(fill
						(type none)
					)
				)
				(arc
					(start 2.54 0)
					(mid 3.048 0.5058)
					(end 3.556 0)
					(stroke
						(width 0)
						(type default)
					)
					(fill
						(type none)
					)
				)
				(arc
					(start 3.556 0)
					(mid 4.064 0.5058)
					(end 4.572 0)
					(stroke
						(width 0)
						(type default)
					)
					(fill
						(type none)
					)
				)
			)
			(symbol "L_4u7_1.55A_Bourns-SRP2512A_1_1"
				(pin passive line
					(at 0 0 0)
					(length 0.508)
					(name "~"
						(effects
							(font
								(size 1.27 1.27)
							)
						)
					)
					(number "1"
						(effects
							(font
								(size 1.27 1.27)
							)
						)
					)
				)
				(pin passive line
					(at 5.08 0 180)
					(length 0.508)
					(name "~"
						(effects
							(font
								(size 1.27 1.27)
							)
						)
					)
					(number "2"
						(effects
							(font
								(size 1.27 1.27)
							)
						)
					)
				)
			)
		)
	(symbol "antmicroInterfaceControllers:EZX710AT2_S_LMR5"
			(exclude_from_sim no)
			(in_bom yes)
			(on_board yes)
			(property "Reference" "U"
				(at 76.2 0 0)
				(effects
					(font
						(size 1.27 1.27)
						(thickness 0.15)
					)
					(justify left bottom)
				)
			)
			(property "Value" "EZX710AT2_S_LMR5"
				(at 76.2 -5.08 0)
				(effects
					(font
						(size 1.27 1.27)
						(thickness 0.15)
					)
					(justify left bottom)
					(hide yes)
				)
			)
			(property "Footprint" "antmicro-footprints:FCBGA-503_22x22mm_Layout21x24_P1mm"
				(at 76.2 -7.62 0)
				(effects
					(font
						(size 1.27 1.27)
						(thickness 0.15)
					)
					(justify left bottom)
					(hide yes)
				)
			)
			(property "Datasheet" "https://www.google.com/url?sa=t&source=web&rct=j&opi=89978449&url=https://cdrdv2-public.intel.com/596333/596333_X710-TM4_Datasheet_v_2_4.pdf&ved=2ahUKEwiSuv20_sCOAxXVCRAIHdxGO_UQFnoECBEQAQ&usg=AOvVaw1CjGyrGWE8ZvOdw4VBsY6U"
				(at 76.2 -10.16 0)
				(effects
					(font
						(size 1.27 1.27)
						(thickness 0.15)
					)
					(justify left bottom)
					(hide yes)
				)
			)
			(property "Description" "Ethernet ICs Intel Ethernet Controller 10 Gigabit X7"
				(at 76.2 -22.86 0)
				(effects
					(font
						(size 1.27 1.27)
						(thickness 0.15)
					)
					(justify left bottom)
					(hide yes)
				)
			)
			(property "MPN" "EZX710AT2 S LMR5"
				(at 76.2 -2.54 0)
				(effects
					(font
						(size 1.27 1.27)
						(thickness 0.15)
					)
					(justify left bottom)
				)
			)
			(property "Manufacturer" "Intel"
				(at 76.2 -15.24 0)
				(effects
					(font
						(size 1.27 1.27)
						(thickness 0.15)
					)
					(justify left bottom)
					(hide yes)
				)
			)
			(property "Author" "Antmicro"
				(at 76.2 -17.78 0)
				(effects
					(font
						(size 1.27 1.27)
						(thickness 0.15)
					)
					(justify left bottom)
					(hide yes)
				)
			)
			(property "License" "Apache-2.0"
				(at 76.2 -20.32 0)
				(effects
					(font
						(size 1.27 1.27)
						(thickness 0.15)
					)
					(justify left bottom)
					(hide yes)
				)
			)
			(property "ki_locked" ""
				(at 0 0 0)
				(effects
					(font
						(size 1.27 1.27)
					)
				)
			)
			(property "ki_keywords" "SMT, IC, ETHERNET"
				(at 0 0 0)
				(effects
					(font
						(size 1.27 1.27)
					)
					(hide yes)
				)
			)
			(symbol "EZX710AT2_S_LMR5_1_1"
				(rectangle
					(start 5.08 2.54)
					(end 30.48 -134.62)
					(stroke
						(width 0.254)
						(type default)
					)
					(fill
						(type background)
					)
				)
				(polyline
					(pts
						(xy 16.51 1.27) (xy 16.51 -133.35)
					)
					(stroke
						(width 0.254)
						(type solid)
					)
					(fill
						(type background)
					)
				)
				(polyline
					(pts
						(xy 24.13 1.27) (xy 24.13 -11.43)
					)
					(stroke
						(width 0.254)
						(type solid)
					)
					(fill
						(type background)
					)
				)
				(text "PCIe"
					(at 21.59 -71.12 900)
					(effects
						(font
							(size 2.54 2.54)
							(thickness 0.508)
							(bold yes)
						)
						(justify left bottom)
					)
				)
				(text "JTAG"
					(at 22.86 -7.112 900)
					(effects
						(font
							(size 1.27 1.27)
							(thickness 0.15)
						)
						(justify left bottom)
					)
				)
				(pin input line
					(at 0 0 0)
					(length 5.08)
					(name "~{PE_RST}"
						(effects
							(font
								(size 1.27 1.27)
							)
						)
					)
					(number "R1"
						(effects
							(font
								(size 1.27 1.27)
							)
						)
					)
				)
				(pin open_collector line
					(at 0 -2.54 0)
					(length 5.08)
					(name "~{PE_WAKE}"
						(effects
							(font
								(size 1.27 1.27)
							)
						)
					)
					(number "P2"
						(effects
							(font
								(size 1.27 1.27)
							)
						)
					)
				)
				(pin input line
					(at 0 -7.62 0)
					(length 5.08)
					(name "PE_CLK_P"
						(effects
							(font
								(size 1.27 1.27)
							)
						)
					)
					(number "AA1"
						(effects
							(font
								(size 1.27 1.27)
							)
						)
					)
				)
				(pin input line
					(at 0 -10.16 0)
					(length 5.08)
					(name "PE_CLK_N"
						(effects
							(font
								(size 1.27 1.27)
							)
						)
					)
					(number "AB2"
						(effects
							(font
								(size 1.27 1.27)
							)
						)
					)
				)
				(pin output line
					(at 0 -15.24 0)
					(length 5.08)
					(name "PET_0_P"
						(effects
							(font
								(size 1.27 1.27)
							)
						)
					)
					(number "AD4"
						(effects
							(font
								(size 1.27 1.27)
							)
						)
					)
				)
				(pin output line
					(at 0 -17.78 0)
					(length 5.08)
					(name "PET_0_N"
						(effects
							(font
								(size 1.27 1.27)
							)
						)
					)
					(number "AC5"
						(effects
							(font
								(size 1.27 1.27)
							)
						)
					)
				)
				(pin input line
					(at 0 -22.86 0)
					(length 5.08)
					(name "PER_0_P"
						(effects
							(font
								(size 1.27 1.27)
							)
						)
					)
					(number "AA5"
						(effects
							(font
								(size 1.27 1.27)
							)
						)
					)
				)
				(pin input line
					(at 0 -25.4 0)
					(length 5.08)
					(name "PER_0_N"
						(effects
							(font
								(size 1.27 1.27)
							)
						)
					)
					(number "AA7"
						(effects
							(font
								(size 1.27 1.27)
							)
						)
					)
				)
				(pin output line
					(at 0 -30.48 0)
					(length 5.08)
					(name "PET_1_P"
						(effects
							(font
								(size 1.27 1.27)
							)
						)
					)
					(number "AD8"
						(effects
							(font
								(size 1.27 1.27)
							)
						)
					)
				)
				(pin output line
					(at 0 -33.02 0)
					(length 5.08)
					(name "PET_1_N"
						(effects
							(font
								(size 1.27 1.27)
							)
						)
					)
					(number "AD10"
						(effects
							(font
								(size 1.27 1.27)
							)
						)
					)
				)
				(pin input line
					(at 0 -38.1 0)
					(length 5.08)
					(name "PER_1_P"
						(effects
							(font
								(size 1.27 1.27)
							)
						)
					)
					(number "AB10"
						(effects
							(font
								(size 1.27 1.27)
							)
						)
					)
				)
				(pin input line
					(at 0 -40.64 0)
					(length 5.08)
					(name "PER_1_N"
						(effects
							(font
								(size 1.27 1.27)
							)
						)
					)
					(number "AB12"
						(effects
							(font
								(size 1.27 1.27)
							)
						)
					)
				)
				(pin output line
					(at 0 -45.72 0)
					(length 5.08)
					(name "PET_2_P"
						(effects
							(font
								(size 1.27 1.27)
							)
						)
					)
					(number "AD14"
						(effects
							(font
								(size 1.27 1.27)
							)
						)
					)
				)
				(pin output line
					(at 0 -48.26 0)
					(length 5.08)
					(name "PET_2_N"
						(effects
							(font
								(size 1.27 1.27)
							)
						)
					)
					(number "AD16"
						(effects
							(font
								(size 1.27 1.27)
							)
						)
					)
				)
				(pin input line
					(at 0 -53.34 0)
					(length 5.08)
					(name "PER_2_P"
						(effects
							(font
								(size 1.27 1.27)
							)
						)
					)
					(number "AB16"
						(effects
							(font
								(size 1.27 1.27)
							)
						)
					)
				)
				(pin input line
					(at 0 -55.88 0)
					(length 5.08)
					(name "PER_2_N"
						(effects
							(font
								(size 1.27 1.27)
							)
						)
					)
					(number "AB18"
						(effects
							(font
								(size 1.27 1.27)
							)
						)
					)
				)
				(pin output line
					(at 0 -60.96 0)
					(length 5.08)
					(name "PET_3_P"
						(effects
							(font
								(size 1.27 1.27)
							)
						)
					)
					(number "AD20"
						(effects
							(font
								(size 1.27 1.27)
							)
						)
					)
				)
				(pin output line
					(at 0 -63.5 0)
					(length 5.08)
					(name "PET_3_N"
						(effects
							(font
								(size 1.27 1.27)
							)
						)
					)
					(number "AD22"
						(effects
							(font
								(size 1.27 1.27)
							)
						)
					)
				)
				(pin input line
					(at 0 -68.58 0)
					(length 5.08)
					(name "PER_3_P"
						(effects
							(font
								(size 1.27 1.27)
							)
						)
					)
					(number "AB22"
						(effects
							(font
								(size 1.27 1.27)
							)
						)
					)
				)
				(pin input line
					(at 0 -71.12 0)
					(length 5.08)
					(name "PER_3_N"
						(effects
							(font
								(size 1.27 1.27)
							)
						)
					)
					(number "AB24"
						(effects
							(font
								(size 1.27 1.27)
							)
						)
					)
				)
				(pin output line
					(at 0 -76.2 0)
					(length 5.08)
					(name "PET_4_P"
						(effects
							(font
								(size 1.27 1.27)
							)
						)
					)
					(number "AD26"
						(effects
							(font
								(size 1.27 1.27)
							)
						)
					)
				)
				(pin output line
					(at 0 -78.74 0)
					(length 5.08)
					(name "PET_4_N"
						(effects
							(font
								(size 1.27 1.27)
							)
						)
					)
					(number "AD28"
						(effects
							(font
								(size 1.27 1.27)
							)
						)
					)
				)
				(pin input line
					(at 0 -83.82 0)
					(length 5.08)
					(name "PER_4_P"
						(effects
							(font
								(size 1.27 1.27)
							)
						)
					)
					(number "AA27"
						(effects
							(font
								(size 1.27 1.27)
							)
						)
					)
				)
				(pin input line
					(at 0 -86.36 0)
					(length 5.08)
					(name "PER_4_N"
						(effects
							(font
								(size 1.27 1.27)
							)
						)
					)
					(number "AB28"
						(effects
							(font
								(size 1.27 1.27)
							)
						)
					)
				)
				(pin output line
					(at 0 -91.44 0)
					(length 5.08)
					(name "PET_5_P"
						(effects
							(font
								(size 1.27 1.27)
							)
						)
					)
					(number "AC31"
						(effects
							(font
								(size 1.27 1.27)
							)
						)
					)
				)
				(pin output line
					(at 0 -93.98 0)
					(length 5.08)
					(name "PET_5_N"
						(effects
							(font
								(size 1.27 1.27)
							)
						)
					)
					(number "AD32"
						(effects
							(font
								(size 1.27 1.27)
							)
						)
					)
				)
				(pin input line
					(at 0 -99.06 0)
					(length 5.08)
					(name "PER_5_P"
						(effects
							(font
								(size 1.27 1.27)
							)
						)
					)
					(number "Y30"
						(effects
							(font
								(size 1.27 1.27)
							)
						)
					)
				)
				(pin input line
					(at 0 -101.6 0)
					(length 5.08)
					(name "PER_5_N"
						(effects
							(font
								(size 1.27 1.27)
							)
						)
					)
					(number "AA31"
						(effects
							(font
								(size 1.27 1.27)
							)
						)
					)
				)
				(pin output line
					(at 0 -106.68 0)
					(length 5.08)
					(name "PET_6_P"
						(effects
							(font
								(size 1.27 1.27)
							)
						)
					)
					(number "AC35"
						(effects
							(font
								(size 1.27 1.27)
							)
						)
					)
				)
				(pin output line
					(at 0 -109.22 0)
					(length 5.08)
					(name "PET_6_N"
						(effects
							(font
								(size 1.27 1.27)
							)
						)
					)
					(number "AD36"
						(effects
							(font
								(size 1.27 1.27)
							)
						)
					)
				)
				(pin input line
					(at 0 -114.3 0)
					(length 5.08)
					(name "PER_6_P"
						(effects
							(font
								(size 1.27 1.27)
							)
						)
					)
					(number "Y34"
						(effects
							(font
								(size 1.27 1.27)
							)
						)
					)
				)
				(pin input line
					(at 0 -116.84 0)
					(length 5.08)
					(name "PER_6_N"
						(effects
							(font
								(size 1.27 1.27)
							)
						)
					)
					(number "AA35"
						(effects
							(font
								(size 1.27 1.27)
							)
						)
					)
				)
				(pin output line
					(at 0 -121.92 0)
					(length 5.08)
					(name "PET_7_P"
						(effects
							(font
								(size 1.27 1.27)
							)
						)
					)
					(number "AC39"
						(effects
							(font
								(size 1.27 1.27)
							)
						)
					)
				)
				(pin output line
					(at 0 -124.46 0)
					(length 5.08)
					(name "PET_7_N"
						(effects
							(font
								(size 1.27 1.27)
							)
						)
					)
					(number "AD40"
						(effects
							(font
								(size 1.27 1.27)
							)
						)
					)
				)
				(pin input line
					(at 0 -129.54 0)
					(length 5.08)
					(name "PER_7_P"
						(effects
							(font
								(size 1.27 1.27)
							)
						)
					)
					(number "Y38"
						(effects
							(font
								(size 1.27 1.27)
							)
						)
					)
				)
				(pin input line
					(at 0 -132.08 0)
					(length 5.08)
					(name "PER_7_N"
						(effects
							(font
								(size 1.27 1.27)
							)
						)
					)
					(number "AA39"
						(effects
							(font
								(size 1.27 1.27)
							)
						)
					)
				)
				(pin input line
					(at 35.56 0 180)
					(length 5.08)
					(name "~{JRST}"
						(effects
							(font
								(size 1.27 1.27)
							)
						)
					)
					(number "V36"
						(effects
							(font
								(size 1.27 1.27)
							)
						)
					)
				)
				(pin input line
					(at 35.56 -2.54 180)
					(length 5.08)
					(name "JTCK"
						(effects
							(font
								(size 1.27 1.27)
							)
						)
					)
					(number "U37"
						(effects
							(font
								(size 1.27 1.27)
							)
						)
					)
				)
				(pin input line
					(at 35.56 -5.08 180)
					(length 5.08)
					(name "JTMS"
						(effects
							(font
								(size 1.27 1.27)
							)
						)
					)
					(number "V38"
						(effects
							(font
								(size 1.27 1.27)
							)
						)
					)
				)
				(pin input line
					(at 35.56 -7.62 180)
					(length 5.08)
					(name "JTDI"
						(effects
							(font
								(size 1.27 1.27)
							)
						)
					)
					(number "T36"
						(effects
							(font
								(size 1.27 1.27)
							)
						)
					)
				)
				(pin open_collector line
					(at 35.56 -10.16 180)
					(length 5.08)
					(name "JTDO"
						(effects
							(font
								(size 1.27 1.27)
							)
						)
					)
					(number "T38"
						(effects
							(font
								(size 1.27 1.27)
							)
						)
					)
				)
				(pin passive line
					(at 35.56 -129.54 180)
					(length 5.08)
					(name "RBIAS"
						(effects
							(font
								(size 1.27 1.27)
							)
						)
					)
					(number "Y10"
						(effects
							(font
								(size 1.27 1.27)
							)
						)
					)
				)
				(pin passive line
					(at 35.56 -132.08 180)
					(length 5.08)
					(name "RSENSE"
						(effects
							(font
								(size 1.27 1.27)
							)
						)
					)
					(number "Y12"
						(effects
							(font
								(size 1.27 1.27)
							)
						)
					)
				)
			)
			(symbol "EZX710AT2_S_LMR5_2_1"
				(rectangle
					(start 5.08 2.54)
					(end 40.64 -60.96)
					(stroke
						(width 0.254)
						(type default)
					)
					(fill
						(type background)
					)
				)
				(polyline
					(pts
						(xy 13.97 1.27) (xy 13.97 -26.67)
					)
					(stroke
						(width 0.254)
						(type solid)
					)
					(fill
						(type background)
					)
				)
				(polyline
					(pts
						(xy 17.78 -31.75) (xy 17.78 -59.69)
					)
					(stroke
						(width 0.254)
						(type solid)
					)
					(fill
						(type background)
					)
				)
				(polyline
					(pts
						(xy 31.75 1.27) (xy 31.75 -26.67)
					)
					(stroke
						(width 0.254)
						(type solid)
					)
					(fill
						(type background)
					)
				)
				(text "P0 10GBASE-T"
					(at 15.24 -19.05 900)
					(effects
						(font
							(size 1.27 1.27)
							(thickness 0.15)
						)
						(justify left top)
					)
				)
				(text "LINE INPUT/OUTPUT"
					(at 20.32 -54.61 900)
					(effects
						(font
							(size 1.27 1.27)
							(thickness 0.15)
						)
						(justify left bottom)
					)
				)
				(text "P1 10GBASE-T"
					(at 30.48 -19.05 900)
					(effects
						(font
							(size 1.27 1.27)
							(thickness 0.15)
						)
						(justify left bottom)
					)
				)
				(pin bidirectional line
					(at 0 0 0)
					(length 5.08)
					(name "P0_A_P"
						(effects
							(font
								(size 1.27 1.27)
							)
						)
					)
					(number "B40"
						(effects
							(font
								(size 1.27 1.27)
							)
						)
					)
				)
				(pin bidirectional line
					(at 0 -2.54 0)
					(length 5.08)
					(name "P0_A_N"
						(effects
							(font
								(size 1.27 1.27)
							)
						)
					)
					(number "A39"
						(effects
							(font
								(size 1.27 1.27)
							)
						)
					)
				)
				(pin bidirectional line
					(at 0 -7.62 0)
					(length 5.08)
					(name "P0_B_P"
						(effects
							(font
								(size 1.27 1.27)
							)
						)
					)
					(number "A37"
						(effects
							(font
								(size 1.27 1.27)
							)
						)
					)
				)
				(pin bidirectional line
					(at 0 -10.16 0)
					(length 5.08)
					(name "P0_B_N"
						(effects
							(font
								(size 1.27 1.27)
							)
						)
					)
					(number "B38"
						(effects
							(font
								(size 1.27 1.27)
							)
						)
					)
				)
				(pin bidirectional line
					(at 0 -15.24 0)
					(length 5.08)
					(name "P0_C_P"
						(effects
							(font
								(size 1.27 1.27)
							)
						)
					)
					(number "B36"
						(effects
							(font
								(size 1.27 1.27)
							)
						)
					)
				)
				(pin bidirectional line
					(at 0 -17.78 0)
					(length 5.08)
					(name "P0_C_N"
						(effects
							(font
								(size 1.27 1.27)
							)
						)
					)
					(number "A35"
						(effects
							(font
								(size 1.27 1.27)
							)
						)
					)
				)
				(pin bidirectional line
					(at 0 -22.86 0)
					(length 5.08)
					(name "P0_D_P"
						(effects
							(font
								(size 1.27 1.27)
							)
						)
					)
					(number "A33"
						(effects
							(font
								(size 1.27 1.27)
							)
						)
					)
				)
				(pin bidirectional line
					(at 0 -25.4 0)
					(length 5.08)
					(name "P0_D_N"
						(effects
							(font
								(size 1.27 1.27)
							)
						)
					)
					(number "B34"
						(effects
							(font
								(size 1.27 1.27)
							)
						)
					)
				)
				(pin output line
					(at 0 -33.02 0)
					(length 5.08)
					(name "SER0_TX_P"
						(effects
							(font
								(size 1.27 1.27)
							)
						)
					)
					(number "A17"
						(effects
							(font
								(size 1.27 1.27)
							)
						)
					)
				)
				(pin output line
					(at 0 -35.56 0)
					(length 5.08)
					(name "SER0_TX_N"
						(effects
							(font
								(size 1.27 1.27)
							)
						)
					)
					(number "B18"
						(effects
							(font
								(size 1.27 1.27)
							)
						)
					)
				)
				(pin input line
					(at 0 -40.64 0)
					(length 5.08)
					(name "SER0_RX_P"
						(effects
							(font
								(size 1.27 1.27)
							)
						)
					)
					(number "B14"
						(effects
							(font
								(size 1.27 1.27)
							)
						)
					)
				)
				(pin input line
					(at 0 -43.18 0)
					(length 5.08)
					(name "SER0_RX_N"
						(effects
							(font
								(size 1.27 1.27)
							)
						)
					)
					(number "A13"
						(effects
							(font
								(size 1.27 1.27)
							)
						)
					)
				)
				(pin output line
					(at 0 -48.26 0)
					(length 5.08)
					(name "SER1_TX_P"
						(effects
							(font
								(size 1.27 1.27)
							)
						)
					)
					(number "A9"
						(effects
							(font
								(size 1.27 1.27)
							)
						)
					)
				)
				(pin output line
					(at 0 -50.8 0)
					(length 5.08)
					(name "SER1_TX_N"
						(effects
							(font
								(size 1.27 1.27)
							)
						)
					)
					(number "B10"
						(effects
							(font
								(size 1.27 1.27)
							)
						)
					)
				)
				(pin input line
					(at 0 -55.88 0)
					(length 5.08)
					(name "SER1_RX_P"
						(effects
							(font
								(size 1.27 1.27)
							)
						)
					)
					(number "B6"
						(effects
							(font
								(size 1.27 1.27)
							)
						)
					)
				)
				(pin input line
					(at 0 -58.42 0)
					(length 5.08)
					(name "SER1_RX_N"
						(effects
							(font
								(size 1.27 1.27)
							)
						)
					)
					(number "A5"
						(effects
							(font
								(size 1.27 1.27)
							)
						)
					)
				)
				(pin bidirectional line
					(at 45.72 0 180)
					(length 5.08)
					(name "P1_A_P"
						(effects
							(font
								(size 1.27 1.27)
							)
						)
					)
					(number "A23"
						(effects
							(font
								(size 1.27 1.27)
							)
						)
					)
				)
				(pin bidirectional line
					(at 45.72 -2.54 180)
					(length 5.08)
					(name "P1_A_N"
						(effects
							(font
								(size 1.27 1.27)
							)
						)
					)
					(number "B24"
						(effects
							(font
								(size 1.27 1.27)
							)
						)
					)
				)
				(pin bidirectional line
					(at 45.72 -7.62 180)
					(length 5.08)
					(name "P1_B_P"
						(effects
							(font
								(size 1.27 1.27)
							)
						)
					)
					(number "B26"
						(effects
							(font
								(size 1.27 1.27)
							)
						)
					)
				)
				(pin bidirectional line
					(at 45.72 -10.16 180)
					(length 5.08)
					(name "P1_B_N"
						(effects
							(font
								(size 1.27 1.27)
							)
						)
					)
					(number "A25"
						(effects
							(font
								(size 1.27 1.27)
							)
						)
					)
				)
				(pin bidirectional line
					(at 45.72 -15.24 180)
					(length 5.08)
					(name "P1_C_P"
						(effects
							(font
								(size 1.27 1.27)
							)
						)
					)
					(number "A27"
						(effects
							(font
								(size 1.27 1.27)
							)
						)
					)
				)
				(pin bidirectional line
					(at 45.72 -17.78 180)
					(length 5.08)
					(name "P1_C_N"
						(effects
							(font
								(size 1.27 1.27)
							)
						)
					)
					(number "B28"
						(effects
							(font
								(size 1.27 1.27)
							)
						)
					)
				)
				(pin bidirectional line
					(at 45.72 -22.86 180)
					(length 5.08)
					(name "P1_D_P"
						(effects
							(font
								(size 1.27 1.27)
							)
						)
					)
					(number "B30"
						(effects
							(font
								(size 1.27 1.27)
							)
						)
					)
				)
				(pin bidirectional line
					(at 45.72 -25.4 180)
					(length 5.08)
					(name "P1_D_N"
						(effects
							(font
								(size 1.27 1.27)
							)
						)
					)
					(number "A29"
						(effects
							(font
								(size 1.27 1.27)
							)
						)
					)
				)
				(pin passive line
					(at 45.72 -55.88 180)
					(length 5.08)
					(name "BIAS_RDAC"
						(effects
							(font
								(size 1.27 1.27)
							)
						)
					)
					(number "E39"
						(effects
							(font
								(size 1.27 1.27)
							)
						)
					)
				)
				(pin passive line
					(at 45.72 -58.42 180)
					(length 5.08)
					(name "RESCAL_RES_P"
						(effects
							(font
								(size 1.27 1.27)
							)
						)
					)
					(number "J37"
						(effects
							(font
								(size 1.27 1.27)
							)
						)
					)
				)
			)
			(symbol "EZX710AT2_S_LMR5_3_1"
				(rectangle
					(start 5.08 2.54)
					(end 40.64 -66.04)
					(stroke
						(width 0.254)
						(type default)
					)
					(fill
						(type background)
					)
				)
				(polyline
					(pts
						(xy 13.97 -29.21) (xy 13.97 -39.37)
					)
					(stroke
						(width 0.254)
						(type solid)
					)
					(fill
						(type background)
					)
				)
				(polyline
					(pts
						(xy 13.97 -41.91) (xy 13.97 -52.07)
					)
					(stroke
						(width 0.254)
						(type solid)
					)
					(fill
						(type background)
					)
				)
				(polyline
					(pts
						(xy 17.78 -6.35) (xy 17.78 -26.67)
					)
					(stroke
						(width 0.254)
						(type solid)
					)
					(fill
						(type background)
					)
				)
				(polyline
					(pts
						(xy 31.75 1.27) (xy 31.75 -8.89)
					)
					(stroke
						(width 0.254)
						(type solid)
					)
					(fill
						(type background)
					)
				)
				(polyline
					(pts
						(xy 31.75 -11.43) (xy 31.75 -21.59)
					)
					(stroke
						(width 0.254)
						(type solid)
					)
					(fill
						(type background)
					)
				)
				(polyline
					(pts
						(xy 31.75 -29.21) (xy 31.75 -39.37)
					)
					(stroke
						(width 0.254)
						(type solid)
					)
					(fill
						(type background)
					)
				)
				(polyline
					(pts
						(xy 31.75 -41.91) (xy 31.75 -52.07)
					)
					(stroke
						(width 0.254)
						(type solid)
					)
					(fill
						(type background)
					)
				)
				(text "P0 SDP"
					(at 16.51 -37.592 900)
					(effects
						(font
							(size 1.27 1.27)
							(thickness 0.15)
						)
						(justify left bottom)
					)
				)
				(text "P1 SDP"
					(at 16.51 -50.8 900)
					(effects
						(font
							(size 1.27 1.27)
							(thickness 0.15)
						)
						(justify left bottom)
					)
				)
				(text "NC (pull-up)"
					(at 19.812 -23.368 900)
					(effects
						(font
							(size 1.27 1.27)
							(thickness 0.15)
						)
						(justify left bottom)
					)
				)
				(text "P3 SDP"
					(at 30.226 -37.846 900)
					(effects
						(font
							(size 1.27 1.27)
							(thickness 0.15)
						)
						(justify left bottom)
					)
				)
				(text "P0 LED"
					(at 30.48 -1.778 0)
					(effects
						(font
							(size 1.27 1.27)
							(thickness 0.15)
						)
						(justify right bottom)
					)
				)
				(text "P2 LED"
					(at 30.48 -6.858 0)
					(effects
						(font
							(size 1.27 1.27)
							(thickness 0.15)
						)
						(justify right bottom)
					)
				)
				(text "P1 LED"
					(at 30.48 -14.732 0)
					(effects
						(font
							(size 1.27 1.27)
							(thickness 0.15)
						)
						(justify right bottom)
					)
				)
				(text "P3 LED"
					(at 30.48 -19.558 0)
					(effects
						(font
							(size 1.27 1.27)
							(thickness 0.15)
						)
						(justify right bottom)
					)
				)
				(text "P3 SDP"
					(at 30.48 -51.054 900)
					(effects
						(font
							(size 1.27 1.27)
							(thickness 0.15)
						)
						(justify left bottom)
					)
				)
				(pin bidirectional line
					(at 0 0 0)
					(length 5.08)
					(name "MDIO0_SDA0"
						(effects
							(font
								(size 1.27 1.27)
							)
						)
					)
					(number "N1"
						(effects
							(font
								(size 1.27 1.27)
							)
						)
					)
				)
				(pin output line
					(at 0 -2.54 0)
					(length 5.08)
					(name "MDC0_SCL0"
						(effects
							(font
								(size 1.27 1.27)
							)
						)
					)
					(number "N3"
						(effects
							(font
								(size 1.27 1.27)
							)
						)
					)
				)
				(pin passive line
					(at 0 -7.62 0)
					(length 5.08)
					(name "MDIO1_SDA1"
						(effects
							(font
								(size 1.27 1.27)
							)
						)
					)
					(number "M2"
						(effects
							(font
								(size 1.27 1.27)
							)
						)
					)
				)
				(pin passive line
					(at 0 -10.16 0)
					(length 5.08)
					(name "MDC1_SCL1"
						(effects
							(font
								(size 1.27 1.27)
							)
						)
					)
					(number "M4"
						(effects
							(font
								(size 1.27 1.27)
							)
						)
					)
				)
				(pin passive line
					(at 0 -15.24 0)
					(length 5.08)
					(name "MDIO2_SDA2"
						(effects
							(font
								(size 1.27 1.27)
							)
						)
					)
					(number "L1"
						(effects
							(font
								(size 1.27 1.27)
							)
						)
					)
				)
				(pin passive line
					(at 0 -17.78 0)
					(length 5.08)
					(name "MDC2_SCL2"
						(effects
							(font
								(size 1.27 1.27)
							)
						)
					)
					(number "L3"
						(effects
							(font
								(size 1.27 1.27)
							)
						)
					)
				)
				(pin passive line
					(at 0 -22.86 0)
					(length 5.08)
					(name "MDIO3_SDA3"
						(effects
							(font
								(size 1.27 1.27)
							)
						)
					)
					(number "K2"
						(effects
							(font
								(size 1.27 1.27)
							)
						)
					)
				)
				(pin passive line
					(at 0 -25.4 0)
					(length 5.08)
					(name "MDC3_SCL3"
						(effects
							(font
								(size 1.27 1.27)
							)
						)
					)
					(number "K4"
						(effects
							(font
								(size 1.27 1.27)
							)
						)
					)
				)
				(pin tri_state line
					(at 0 -30.48 0)
					(length 5.08)
					(name "SDP0_0"
						(effects
							(font
								(size 1.27 1.27)
							)
						)
					)
					(number "E5"
						(effects
							(font
								(size 1.27 1.27)
							)
						)
					)
				)
				(pin tri_state line
					(at 0 -33.02 0)
					(length 5.08)
					(name "SDP0_1"
						(effects
							(font
								(size 1.27 1.27)
							)
						)
					)
					(number "G5"
						(effects
							(font
								(size 1.27 1.27)
							)
						)
					)
				)
				(pin tri_state line
					(at 0 -35.56 0)
					(length 5.08)
					(name "SDP0_2"
						(effects
							(font
								(size 1.27 1.27)
							)
						)
					)
					(number "K6"
						(effects
							(font
								(size 1.27 1.27)
							)
						)
					)
				)
				(pin passive line
					(at 0 -38.1 0)
					(length 5.08)
					(name "SDP0_3"
						(effects
							(font
								(size 1.27 1.27)
							)
						)
					)
					(number "L5"
						(effects
							(font
								(size 1.27 1.27)
							)
						)
					)
				)
				(pin passive line
					(at 0 -43.18 0)
					(length 5.08)
					(name "SDP1_0"
						(effects
							(font
								(size 1.27 1.27)
							)
						)
					)
					(number "R7"
						(effects
							(font
								(size 1.27 1.27)
							)
						)
					)
				)
				(pin passive line
					(at 0 -45.72 0)
					(length 5.08)
					(name "SDP1_1"
						(effects
							(font
								(size 1.27 1.27)
							)
						)
					)
					(number "P4"
						(effects
							(font
								(size 1.27 1.27)
							)
						)
					)
				)
				(pin passive line
					(at 0 -48.26 0)
					(length 5.08)
					(name "SDP1_2"
						(effects
							(font
								(size 1.27 1.27)
							)
						)
					)
					(number "P6"
						(effects
							(font
								(size 1.27 1.27)
							)
						)
					)
				)
				(pin passive line
					(at 0 -50.8 0)
					(length 5.08)
					(name "SDP1_3"
						(effects
							(font
								(size 1.27 1.27)
							)
						)
					)
					(number "H6"
						(effects
							(font
								(size 1.27 1.27)
							)
						)
					)
				)
				(pin input line
					(at 0 -55.88 0)
					(length 5.08)
					(name "REFCLKIN_P"
						(effects
							(font
								(size 1.27 1.27)
							)
						)
					)
					(number "C1"
						(effects
							(font
								(size 1.27 1.27)
							)
						)
					)
					(alternate "XTAL_IN" input line)
				)
				(pin input line
					(at 0 -58.42 0)
					(length 5.08)
					(name "REFCLKIN_N"
						(effects
							(font
								(size 1.27 1.27)
							)
						)
					)
					(number "C3"
						(effects
							(font
								(size 1.27 1.27)
							)
						)
					)
					(alternate "XTAL_OUT" output line)
				)
				(pin tri_state line
					(at 0 -63.5 0)
					(length 5.08)
					(name "OSC_SEL"
						(effects
							(font
								(size 1.27 1.27)
							)
						)
					)
					(number "J9"
						(effects
							(font
								(size 1.27 1.27)
							)
						)
					)
				)
				(pin output line
					(at 45.72 0 180)
					(length 5.08)
					(name "LED0_0"
						(effects
							(font
								(size 1.27 1.27)
							)
						)
					)
					(number "V4"
						(effects
							(font
								(size 1.27 1.27)
							)
						)
					)
				)
				(pin output line
					(at 45.72 -2.54 180)
					(length 5.08)
					(name "LED0_1"
						(effects
							(font
								(size 1.27 1.27)
							)
						)
					)
					(number "V6"
						(effects
							(font
								(size 1.27 1.27)
							)
						)
					)
				)
				(pin output line
					(at 45.72 -5.08 180)
					(length 5.08)
					(name "LED2_0"
						(effects
							(font
								(size 1.27 1.27)
							)
						)
					)
					(number "T4"
						(effects
							(font
								(size 1.27 1.27)
							)
						)
					)
				)
				(pin output line
					(at 45.72 -7.62 180)
					(length 5.08)
					(name "LED2_1"
						(effects
							(font
								(size 1.27 1.27)
							)
						)
					)
					(number "T6"
						(effects
							(font
								(size 1.27 1.27)
							)
						)
					)
				)
				(pin passive line
					(at 45.72 -12.7 180)
					(length 5.08)
					(name "LED1_0"
						(effects
							(font
								(size 1.27 1.27)
							)
						)
					)
					(number "U5"
						(effects
							(font
								(size 1.27 1.27)
							)
						)
					)
				)
				(pin passive line
					(at 45.72 -15.24 180)
					(length 5.08)
					(name "LED1_1"
						(effects
							(font
								(size 1.27 1.27)
							)
						)
					)
					(number "U7"
						(effects
							(font
								(size 1.27 1.27)
							)
						)
					)
				)
				(pin passive line
					(at 45.72 -17.78 180)
					(length 5.08)
					(name "LED3_0"
						(effects
							(font
								(size 1.27 1.27)
							)
						)
					)
					(number "R3"
						(effects
							(font
								(size 1.27 1.27)
							)
						)
					)
				)
				(pin passive line
					(at 45.72 -20.32 180)
					(length 5.08)
					(name "LED3_1"
						(effects
							(font
								(size 1.27 1.27)
							)
						)
					)
					(number "R5"
						(effects
							(font
								(size 1.27 1.27)
							)
						)
					)
				)
				(pin passive line
					(at 45.72 -30.48 180)
					(length 5.08)
					(name "SDP2_0"
						(effects
							(font
								(size 1.27 1.27)
							)
						)
					)
					(number "F6"
						(effects
							(font
								(size 1.27 1.27)
							)
						)
					)
				)
				(pin passive line
					(at 45.72 -33.02 180)
					(length 5.08)
					(name "SDP2_1"
						(effects
							(font
								(size 1.27 1.27)
							)
						)
					)
					(number "J7"
						(effects
							(font
								(size 1.27 1.27)
							)
						)
					)
				)
				(pin passive line
					(at 45.72 -35.56 180)
					(length 5.08)
					(name "SDP2_2"
						(effects
							(font
								(size 1.27 1.27)
							)
						)
					)
					(number "E7"
						(effects
							(font
								(size 1.27 1.27)
							)
						)
					)
				)
				(pin passive line
					(at 45.72 -38.1 180)
					(length 5.08)
					(name "SDP2_3"
						(effects
							(font
								(size 1.27 1.27)
							)
						)
					)
					(number "G7"
						(effects
							(font
								(size 1.27 1.27)
							)
						)
					)
				)
				(pin passive line
					(at 45.72 -43.18 180)
					(length 5.08)
					(name "SDP3_0"
						(effects
							(font
								(size 1.27 1.27)
							)
						)
					)
					(number "N5"
						(effects
							(font
								(size 1.27 1.27)
							)
						)
					)
				)
				(pin passive line
					(at 45.72 -45.72 180)
					(length 5.08)
					(name "SDP3_1"
						(effects
							(font
								(size 1.27 1.27)
							)
						)
					)
					(number "N7"
						(effects
							(font
								(size 1.27 1.27)
							)
						)
					)
				)
				(pin passive line
					(at 45.72 -48.26 180)
					(length 5.08)
					(name "SDP3_2"
						(effects
							(font
								(size 1.27 1.27)
							)
						)
					)
					(number "M6"
						(effects
							(font
								(size 1.27 1.27)
							)
						)
					)
				)
				(pin passive line
					(at 45.72 -50.8 180)
					(length 5.08)
					(name "SDP3_3"
						(effects
							(font
								(size 1.27 1.27)
							)
						)
					)
					(number "M8"
						(effects
							(font
								(size 1.27 1.27)
							)
						)
					)
				)
				(pin passive line
					(at 45.72 -60.96 180)
					(length 5.08)
					(name "TPIN_5"
						(effects
							(font
								(size 1.27 1.27)
							)
						)
					)
					(number "G17"
						(effects
							(font
								(size 1.27 1.27)
							)
						)
					)
				)
				(pin passive line
					(at 45.72 -63.5 180)
					(length 5.08)
					(name "TPIN_3"
						(effects
							(font
								(size 1.27 1.27)
							)
						)
					)
					(number "H20"
						(effects
							(font
								(size 1.27 1.27)
							)
						)
					)
				)
			)
			(symbol "EZX710AT2_S_LMR5_4_1"
				(rectangle
					(start 5.08 2.54)
					(end 40.64 -50.8)
					(stroke
						(width 0.254)
						(type default)
					)
					(fill
						(type background)
					)
				)
				(polyline
					(pts
						(xy 20.32 -26.67) (xy 20.32 1.27)
					)
					(stroke
						(width 0.254)
						(type solid)
					)
					(fill
						(type background)
					)
				)
				(polyline
					(pts
						(xy 29.21 -39.37) (xy 29.21 -49.53)
					)
					(stroke
						(width 0.254)
						(type solid)
					)
					(fill
						(type background)
					)
				)
				(polyline
					(pts
						(xy 30.48 -31.75) (xy 30.48 -24.13)
					)
					(stroke
						(width 0.254)
						(type solid)
					)
					(fill
						(type background)
					)
				)
				(polyline
					(pts
						(xy 31.75 1.27) (xy 31.75 -13.97)
					)
					(stroke
						(width 0.254)
						(type solid)
					)
					(fill
						(type background)
					)
				)
				(text "NC-SI"
					(at 22.86 -16.256 900)
					(effects
						(font
							(size 1.27 1.27)
							(thickness 0.15)
						)
						(justify left bottom)
					)
				)
				(text "SMBus"
					(at 27.94 -30.988 900)
					(effects
						(font
							(size 1.27 1.27)
							(thickness 0.15)
						)
						(justify left top)
					)
				)
				(text "Flash"
					(at 27.94 -47.244 900)
					(effects
						(font
							(size 1.27 1.27)
							(thickness 0.15)
						)
						(justify left bottom)
					)
				)
				(text "GPIO"
					(at 30.48 -8.636 900)
					(effects
						(font
							(size 1.27 1.27)
							(thickness 0.15)
						)
						(justify left bottom)
					)
				)
				(pin input line
					(at 0 0 0)
					(length 5.08)
					(name "NCSI_ARB_IN"
						(effects
							(font
								(size 1.27 1.27)
							)
						)
					)
					(number "G3"
						(effects
							(font
								(size 1.27 1.27)
							)
						)
					)
				)
				(pin output line
					(at 0 -2.54 0)
					(length 5.08)
					(name "NCSI_ARB_OUT"
						(effects
							(font
								(size 1.27 1.27)
							)
						)
					)
					(number "F4"
						(effects
							(font
								(size 1.27 1.27)
							)
						)
					)
				)
				(pin input line
					(at 0 -5.08 0)
					(length 5.08)
					(name "NCSI_CLK_IN"
						(effects
							(font
								(size 1.27 1.27)
							)
						)
					)
					(number "H2"
						(effects
							(font
								(size 1.27 1.27)
							)
						)
					)
				)
				(pin output line
					(at 0 -7.62 0)
					(length 5.08)
					(name "NCSI_CRS_DV"
						(effects
							(font
								(size 1.27 1.27)
							)
						)
					)
					(number "J5"
						(effects
							(font
								(size 1.27 1.27)
							)
						)
					)
				)
				(pin input line
					(at 0 -10.16 0)
					(length 5.08)
					(name "NCSI_TX_EN"
						(effects
							(font
								(size 1.27 1.27)
							)
						)
					)
					(number "H4"
						(effects
							(font
								(size 1.27 1.27)
							)
						)
					)
				)
				(pin input line
					(at 0 -15.24 0)
					(length 5.08)
					(name "NCSI_TXD_0"
						(effects
							(font
								(size 1.27 1.27)
							)
						)
					)
					(number "F2"
						(effects
							(font
								(size 1.27 1.27)
							)
						)
					)
				)
				(pin output line
					(at 0 -17.78 0)
					(length 5.08)
					(name "NCSI_RXD_0"
						(effects
							(font
								(size 1.27 1.27)
							)
						)
					)
					(number "J1"
						(effects
							(font
								(size 1.27 1.27)
							)
						)
					)
				)
				(pin input line
					(at 0 -22.86 0)
					(length 5.08)
					(name "NCSI_TXD_1"
						(effects
							(font
								(size 1.27 1.27)
							)
						)
					)
					(number "G1"
						(effects
							(font
								(size 1.27 1.27)
							)
						)
					)
				)
				(pin output line
					(at 0 -25.4 0)
					(length 5.08)
					(name "NCSI_RXD_1"
						(effects
							(font
								(size 1.27 1.27)
							)
						)
					)
					(number "J3"
						(effects
							(font
								(size 1.27 1.27)
							)
						)
					)
				)
				(pin tri_state line
					(at 0 -33.02 0)
					(length 5.08)
					(name "~{DEV_DIS}"
						(effects
							(font
								(size 1.27 1.27)
							)
						)
					)
					(number "D2"
						(effects
							(font
								(size 1.27 1.27)
							)
						)
					)
				)
				(pin tri_state line
					(at 0 -35.56 0)
					(length 5.08)
					(name "~{PCI_DIS}"
						(effects
							(font
								(size 1.27 1.27)
							)
						)
					)
					(number "U3"
						(effects
							(font
								(size 1.27 1.27)
							)
						)
					)
				)
				(pin input line
					(at 0 -40.64 0)
					(length 5.08)
					(name "MAIN_PWR_OK"
						(effects
							(font
								(size 1.27 1.27)
							)
						)
					)
					(number "E3"
						(effects
							(font
								(size 1.27 1.27)
							)
						)
					)
				)
				(pin tri_state line
					(at 0 -43.18 0)
					(length 5.08)
					(name "AUX_PWR"
						(effects
							(font
								(size 1.27 1.27)
							)
						)
					)
					(number "E1"
						(effects
							(font
								(size 1.27 1.27)
							)
						)
					)
				)
				(pin input line
					(at 0 -45.72 0)
					(length 5.08)
					(name "POR_BYPASS"
						(effects
							(font
								(size 1.27 1.27)
							)
						)
					)
					(number "U39"
						(effects
							(font
								(size 1.27 1.27)
							)
						)
					)
				)
				(pin input line
					(at 0 -48.26 0)
					(length 5.08)
					(name "LAN_PWR_GOOD"
						(effects
							(font
								(size 1.27 1.27)
							)
						)
					)
					(number "AB42"
						(effects
							(font
								(size 1.27 1.27)
							)
						)
					)
				)
				(pin tri_state line
					(at 45.72 0 180)
					(length 5.08)
					(name "GPIO_0"
						(effects
							(font
								(size 1.27 1.27)
							)
						)
					)
					(number "V40"
						(effects
							(font
								(size 1.27 1.27)
							)
						)
					)
				)
				(pin passive line
					(at 45.72 -2.54 180)
					(length 5.08)
					(name "GPIO_1"
						(effects
							(font
								(size 1.27 1.27)
							)
						)
					)
					(number "W41"
						(effects
							(font
								(size 1.27 1.27)
							)
						)
					)
				)
				(pin tri_state line
					(at 45.72 -5.08 180)
					(length 5.08)
					(name "GPIO_2"
						(effects
							(font
								(size 1.27 1.27)
							)
						)
					)
					(number "Y42"
						(effects
							(font
								(size 1.27 1.27)
							)
						)
					)
				)
				(pin passive line
					(at 45.72 -7.62 180)
					(length 5.08)
					(name "GPIO_3"
						(effects
							(font
								(size 1.27 1.27)
							)
						)
					)
					(number "V42"
						(effects
							(font
								(size 1.27 1.27)
							)
						)
					)
				)
				(pin passive line
					(at 45.72 -10.16 180)
					(length 5.08)
					(name "GPIO_4"
						(effects
							(font
								(size 1.27 1.27)
							)
						)
					)
					(number "H8"
						(effects
							(font
								(size 1.27 1.27)
							)
						)
					)
				)
				(pin tri_state line
					(at 45.72 -12.7 180)
					(length 5.08)
					(name "GPIO_5"
						(effects
							(font
								(size 1.27 1.27)
							)
						)
					)
					(number "L7"
						(effects
							(font
								(size 1.27 1.27)
							)
						)
					)
				)
				(pin open_collector line
					(at 45.72 -25.4 180)
					(length 5.08)
					(name "~{SMBALRT}"
						(effects
							(font
								(size 1.27 1.27)
							)
						)
					)
					(number "U41"
						(effects
							(font
								(size 1.27 1.27)
							)
						)
					)
				)
				(pin open_collector line
					(at 45.72 -27.94 180)
					(length 5.08)
					(name "SMBCLK"
						(effects
							(font
								(size 1.27 1.27)
							)
						)
					)
					(number "R39"
						(effects
							(font
								(size 1.27 1.27)
							)
						)
					)
				)
				(pin open_collector line
					(at 45.72 -30.48 180)
					(length 5.08)
					(name "SMBD"
						(effects
							(font
								(size 1.27 1.27)
							)
						)
					)
					(number "T40"
						(effects
							(font
								(size 1.27 1.27)
							)
						)
					)
				)
				(pin tri_state line
					(at 45.72 -40.64 180)
					(length 5.08)
					(name "~{FLSH_CE}"
						(effects
							(font
								(size 1.27 1.27)
							)
						)
					)
					(number "R41"
						(effects
							(font
								(size 1.27 1.27)
							)
						)
					)
				)
				(pin tri_state line
					(at 45.72 -43.18 180)
					(length 5.08)
					(name "FLSH_SCK"
						(effects
							(font
								(size 1.27 1.27)
							)
						)
					)
					(number "P40"
						(effects
							(font
								(size 1.27 1.27)
							)
						)
					)
				)
				(pin tri_state line
					(at 45.72 -45.72 180)
					(length 5.08)
					(name "FLSH_SI"
						(effects
							(font
								(size 1.27 1.27)
							)
						)
					)
					(number "P42"
						(effects
							(font
								(size 1.27 1.27)
							)
						)
					)
				)
				(pin input line
					(at 45.72 -48.26 180)
					(length 5.08)
					(name "FLSH_SO"
						(effects
							(font
								(size 1.27 1.27)
							)
						)
					)
					(number "T42"
						(effects
							(font
								(size 1.27 1.27)
							)
						)
					)
				)
			)
			(symbol "EZX710AT2_S_LMR5_5_1"
				(rectangle
					(start 5.08 2.54)
					(end 38.1 -93.98)
					(stroke
						(width 0.254)
						(type default)
					)
					(fill
						(type background)
					)
				)
				(pin passive line
					(at 0 0 0)
					(length 5.08)
					(name "RSVDY24_VSS"
						(effects
							(font
								(size 1.27 1.27)
							)
						)
					)
					(number "Y24"
						(effects
							(font
								(size 1.27 1.27)
							)
						)
					)
					(alternate "RSVD" passive line)
					(alternate "VSS" power_in line)
				)
				(pin passive line
					(at 0 -5.08 0)
					(length 5.08)
					(name "RSVDY22_VSS"
						(effects
							(font
								(size 1.27 1.27)
							)
						)
					)
					(number "Y22"
						(effects
							(font
								(size 1.27 1.27)
							)
						)
					)
					(alternate "RSVD" passive line)
					(alternate "VSS" power_in line)
				)
				(pin passive line
					(at 0 -7.62 0)
					(length 5.08)
					(name "RSVDW5_VSS"
						(effects
							(font
								(size 1.27 1.27)
							)
						)
					)
					(number "W5"
						(effects
							(font
								(size 1.27 1.27)
							)
						)
					)
					(alternate "RSVD" passive line)
					(alternate "VSS" power_in line)
				)
				(pin passive line
					(at 0 -12.7 0)
					(length 5.08)
					(name "RSVDN9_VSS"
						(effects
							(font
								(size 1.27 1.27)
							)
						)
					)
					(number "N9"
						(effects
							(font
								(size 1.27 1.27)
							)
						)
					)
					(alternate "RSVD" passive line)
					(alternate "VSS" power_in line)
				)
				(pin passive line
					(at 0 -15.24 0)
					(length 5.08)
					(name "RSVDW1_VSS"
						(effects
							(font
								(size 1.27 1.27)
							)
						)
					)
					(number "W1"
						(effects
							(font
								(size 1.27 1.27)
							)
						)
					)
					(alternate "RSVD" passive line)
					(alternate "VSS" power_in line)
				)
				(pin passive line
					(at 0 -17.78 0)
					(length 5.08)
					(name "RSVDP22_VSS"
						(effects
							(font
								(size 1.27 1.27)
							)
						)
					)
					(number "P22"
						(effects
							(font
								(size 1.27 1.27)
							)
						)
					)
					(alternate "RSVD" passive line)
					(alternate "VSS" power_in line)
				)
				(pin passive line
					(at 0 -20.32 0)
					(length 5.08)
					(name "RSVDY18_VSS"
						(effects
							(font
								(size 1.27 1.27)
							)
						)
					)
					(number "Y18"
						(effects
							(font
								(size 1.27 1.27)
							)
						)
					)
					(alternate "RSVD" passive line)
					(alternate "VSS" power_in line)
				)
				(pin passive line
					(at 0 -24.13 0)
					(length 5.08)
					(name "RSVDP8_VSS"
						(effects
							(font
								(size 1.27 1.27)
							)
						)
					)
					(number "P8"
						(effects
							(font
								(size 1.27 1.27)
							)
						)
					)
					(alternate "RSVD" passive line)
					(alternate "VSS" power_in line)
				)
				(pin passive line
					(at 0 -31.75 0)
					(length 5.08)
					(name "RSVDR9_NC"
						(effects
							(font
								(size 1.27 1.27)
							)
						)
					)
					(number "R9"
						(effects
							(font
								(size 1.27 1.27)
							)
						)
					)
				)
				(pin passive line
					(at 0 -34.29 0)
					(length 5.08)
					(name "RSVDU9_NC"
						(effects
							(font
								(size 1.27 1.27)
							)
						)
					)
					(number "U9"
						(effects
							(font
								(size 1.27 1.27)
							)
						)
					)
				)
				(pin passive line
					(at 0 -36.83 0)
					(length 5.08)
					(name "RSVDK24_NC"
						(effects
							(font
								(size 1.27 1.27)
							)
						)
					)
					(number "K24"
						(effects
							(font
								(size 1.27 1.27)
							)
						)
					)
				)
				(pin passive line
					(at 0 -39.37 0)
					(length 5.08)
					(name "RSVDL25_NC"
						(effects
							(font
								(size 1.27 1.27)
							)
						)
					)
					(number "L25"
						(effects
							(font
								(size 1.27 1.27)
							)
						)
					)
				)
				(pin passive line
					(at 43.18 0 180)
					(length 5.08)
					(name "DEBUG_Y16"
						(effects
							(font
								(size 1.27 1.27)
							)
						)
					)
					(number "Y16"
						(effects
							(font
								(size 1.27 1.27)
							)
						)
					)
				)
				(pin passive line
					(at 43.18 -2.54 180)
					(length 5.08)
					(name "DEBUG_W7"
						(effects
							(font
								(size 1.27 1.27)
							)
						)
					)
					(number "W7"
						(effects
							(font
								(size 1.27 1.27)
							)
						)
					)
				)
				(pin passive line
					(at 43.18 -5.08 180)
					(length 5.08)
					(name "DEBUG_Y20"
						(effects
							(font
								(size 1.27 1.27)
							)
						)
					)
					(number "Y20"
						(effects
							(font
								(size 1.27 1.27)
							)
						)
					)
				)
				(pin passive line
					(at 43.18 -10.16 180)
					(length 5.08)
					(name "RSVDW25_NC"
						(effects
							(font
								(size 1.27 1.27)
							)
						)
					)
					(number "W25"
						(effects
							(font
								(size 1.27 1.27)
							)
						)
					)
				)
				(pin passive line
					(at 43.18 -12.7 180)
					(length 5.08)
					(name "RSVDW27_NC"
						(effects
							(font
								(size 1.27 1.27)
							)
						)
					)
					(number "W27"
						(effects
							(font
								(size 1.27 1.27)
							)
						)
					)
				)
				(pin passive line
					(at 43.18 -15.24 180)
					(length 5.08)
					(name "RSVDV22_NC"
						(effects
							(font
								(size 1.27 1.27)
							)
						)
					)
					(number "V22"
						(effects
							(font
								(size 1.27 1.27)
							)
						)
					)
				)
				(pin passive line
					(at 43.18 -17.78 180)
					(length 5.08)
					(name "RSVDV24_NC"
						(effects
							(font
								(size 1.27 1.27)
							)
						)
					)
					(number "V24"
						(effects
							(font
								(size 1.27 1.27)
							)
						)
					)
				)
				(pin passive line
					(at 43.18 -20.32 180)
					(length 5.08)
					(name "RSVDV26_NC"
						(effects
							(font
								(size 1.27 1.27)
							)
						)
					)
					(number "V26"
						(effects
							(font
								(size 1.27 1.27)
							)
						)
					)
				)
				(pin passive line
					(at 43.18 -22.86 180)
					(length 5.08)
					(name "RSVDV28_NC"
						(effects
							(font
								(size 1.27 1.27)
							)
						)
					)
					(number "V28"
						(effects
							(font
								(size 1.27 1.27)
							)
						)
					)
				)
				(pin passive line
					(at 43.18 -25.4 180)
					(length 5.08)
					(name "RSVDU23_NC"
						(effects
							(font
								(size 1.27 1.27)
							)
						)
					)
					(number "U23"
						(effects
							(font
								(size 1.27 1.27)
							)
						)
					)
				)
				(pin passive line
					(at 43.18 -27.94 180)
					(length 5.08)
					(name "RSVDU25_NC"
						(effects
							(font
								(size 1.27 1.27)
							)
						)
					)
					(number "U25"
						(effects
							(font
								(size 1.27 1.27)
							)
						)
					)
				)
				(pin passive line
					(at 43.18 -30.48 180)
					(length 5.08)
					(name "RSVDU27_NC"
						(effects
							(font
								(size 1.27 1.27)
							)
						)
					)
					(number "U27"
						(effects
							(font
								(size 1.27 1.27)
							)
						)
					)
				)
				(pin passive line
					(at 43.18 -33.02 180)
					(length 5.08)
					(name "RSVDU29_NC"
						(effects
							(font
								(size 1.27 1.27)
							)
						)
					)
					(number "U29"
						(effects
							(font
								(size 1.27 1.27)
							)
						)
					)
				)
				(pin passive line
					(at 43.18 -35.56 180)
					(length 5.08)
					(name "RSVDT22_NC"
						(effects
							(font
								(size 1.27 1.27)
							)
						)
					)
					(number "T22"
						(effects
							(font
								(size 1.27 1.27)
							)
						)
					)
				)
				(pin passive line
					(at 43.18 -38.1 180)
					(length 5.08)
					(name "RSVDT24_NC"
						(effects
							(font
								(size 1.27 1.27)
							)
						)
					)
					(number "T24"
						(effects
							(font
								(size 1.27 1.27)
							)
						)
					)
				)
				(pin passive line
					(at 43.18 -40.64 180)
					(length 5.08)
					(name "RSVDT26_NC"
						(effects
							(font
								(size 1.27 1.27)
							)
						)
					)
					(number "T26"
						(effects
							(font
								(size 1.27 1.27)
							)
						)
					)
				)
				(pin passive line
					(at 43.18 -43.18 180)
					(length 5.08)
					(name "RSVDT28_NC"
						(effects
							(font
								(size 1.27 1.27)
							)
						)
					)
					(number "T28"
						(effects
							(font
								(size 1.27 1.27)
							)
						)
					)
				)
				(pin passive line
					(at 43.18 -45.72 180)
					(length 5.08)
					(name "RSVDR23_NC"
						(effects
							(font
								(size 1.27 1.27)
							)
						)
					)
					(number "R23"
						(effects
							(font
								(size 1.27 1.27)
							)
						)
					)
				)
				(pin passive line
					(at 43.18 -48.26 180)
					(length 5.08)
					(name "RSVDR25_NC"
						(effects
							(font
								(size 1.27 1.27)
							)
						)
					)
					(number "R25"
						(effects
							(font
								(size 1.27 1.27)
							)
						)
					)
				)
				(pin passive line
					(at 43.18 -50.8 180)
					(length 5.08)
					(name "RSVDR27_NC"
						(effects
							(font
								(size 1.27 1.27)
							)
						)
					)
					(number "R27"
						(effects
							(font
								(size 1.27 1.27)
							)
						)
					)
				)
				(pin passive line
					(at 43.18 -53.34 180)
					(length 5.08)
					(name "RSVDP24_NC"
						(effects
							(font
								(size 1.27 1.27)
							)
						)
					)
					(number "P24"
						(effects
							(font
								(size 1.27 1.27)
							)
						)
					)
				)
				(pin passive line
					(at 43.18 -55.88 180)
					(length 5.08)
					(name "RSVDP26_NC"
						(effects
							(font
								(size 1.27 1.27)
							)
						)
					)
					(number "P26"
						(effects
							(font
								(size 1.27 1.27)
							)
						)
					)
				)
				(pin passive line
					(at 43.18 -58.42 180)
					(length 5.08)
					(name "RSVDP28_NC"
						(effects
							(font
								(size 1.27 1.27)
							)
						)
					)
					(number "P28"
						(effects
							(font
								(size 1.27 1.27)
							)
						)
					)
				)
				(pin passive line
					(at 43.18 -60.96 180)
					(length 5.08)
					(name "RSVDN23_NC"
						(effects
							(font
								(size 1.27 1.27)
							)
						)
					)
					(number "N23"
						(effects
							(font
								(size 1.27 1.27)
							)
						)
					)
				)
				(pin passive line
					(at 43.18 -63.5 180)
					(length 5.08)
					(name "RSVDN25_NC"
						(effects
							(font
								(size 1.27 1.27)
							)
						)
					)
					(number "N25"
						(effects
							(font
								(size 1.27 1.27)
							)
						)
					)
				)
				(pin passive line
					(at 43.18 -66.04 180)
					(length 5.08)
					(name "RSVDN27_NC"
						(effects
							(font
								(size 1.27 1.27)
							)
						)
					)
					(number "N27"
						(effects
							(font
								(size 1.27 1.27)
							)
						)
					)
				)
				(pin passive line
					(at 43.18 -68.58 180)
					(length 5.08)
					(name "RSVDM22_NC"
						(effects
							(font
								(size 1.27 1.27)
							)
						)
					)
					(number "M22"
						(effects
							(font
								(size 1.27 1.27)
							)
						)
					)
				)
				(pin passive line
					(at 43.18 -71.12 180)
					(length 5.08)
					(name "RSVDM24_NC"
						(effects
							(font
								(size 1.27 1.27)
							)
						)
					)
					(number "M24"
						(effects
							(font
								(size 1.27 1.27)
							)
						)
					)
				)
				(pin passive line
					(at 43.18 -73.66 180)
					(length 5.08)
					(name "RSVDM26_NC"
						(effects
							(font
								(size 1.27 1.27)
							)
						)
					)
					(number "M26"
						(effects
							(font
								(size 1.27 1.27)
							)
						)
					)
				)
				(pin passive line
					(at 43.18 -76.2 180)
					(length 5.08)
					(name "RSVDM28_NC"
						(effects
							(font
								(size 1.27 1.27)
							)
						)
					)
					(number "M28"
						(effects
							(font
								(size 1.27 1.27)
							)
						)
					)
				)
				(pin passive line
					(at 43.18 -78.74 180)
					(length 5.08)
					(name "RSVDL23_NC"
						(effects
							(font
								(size 1.27 1.27)
							)
						)
					)
					(number "L23"
						(effects
							(font
								(size 1.27 1.27)
							)
						)
					)
				)
				(pin passive line
					(at 43.18 -81.28 180)
					(length 5.08)
					(name "RSVDL27_NC"
						(effects
							(font
								(size 1.27 1.27)
							)
						)
					)
					(number "L27"
						(effects
							(font
								(size 1.27 1.27)
							)
						)
					)
				)
				(pin passive line
					(at 43.18 -83.82 180)
					(length 5.08)
					(name "RSVDK22_NC"
						(effects
							(font
								(size 1.27 1.27)
							)
						)
					)
					(number "K22"
						(effects
							(font
								(size 1.27 1.27)
							)
						)
					)
				)
				(pin passive line
					(at 43.18 -86.36 180)
					(length 5.08)
					(name "RSVDJ23_NC"
						(effects
							(font
								(size 1.27 1.27)
							)
						)
					)
					(number "J23"
						(effects
							(font
								(size 1.27 1.27)
							)
						)
					)
				)
				(pin passive line
					(at 43.18 -88.9 180)
					(length 5.08)
					(name "RSVDJ25_NC"
						(effects
							(font
								(size 1.27 1.27)
							)
						)
					)
					(number "J25"
						(effects
							(font
								(size 1.27 1.27)
							)
						)
					)
				)
				(pin passive line
					(at 43.18 -91.44 180)
					(length 5.08)
					(name "RSVDW23_NC"
						(effects
							(font
								(size 1.27 1.27)
							)
						)
					)
					(number "W23"
						(effects
							(font
								(size 1.27 1.27)
							)
						)
					)
				)
			)
			(symbol "EZX710AT2_S_LMR5_6_1"
				(rectangle
					(start 5.08 2.54)
					(end 50.8 -88.9)
					(stroke
						(width 0.254)
						(type default)
					)
					(fill
						(type background)
					)
				)
				(polyline
					(pts
						(xy 20.32 -26.924) (xy 20.32 -34.544)
					)
					(stroke
						(width 0.254)
						(type solid)
					)
					(fill
						(type background)
					)
				)
				(polyline
					(pts
						(xy 20.32 -54.61) (xy 20.32 -59.69)
					)
					(stroke
						(width 0.254)
						(type solid)
					)
					(fill
						(type background)
					)
				)
				(polyline
					(pts
						(xy 20.32 -62.23) (xy 20.32 -77.47)
					)
					(stroke
						(width 0.254)
						(type solid)
					)
					(fill
						(type background)
					)
				)
				(polyline
					(pts
						(xy 22.86 1.27) (xy 22.86 -8.89)
					)
					(stroke
						(width 0.254)
						(type solid)
					)
					(fill
						(type background)
					)
				)
				(polyline
					(pts
						(xy 22.86 -11.43) (xy 22.86 -16.51)
					)
					(stroke
						(width 0.254)
						(type solid)
					)
					(fill
						(type background)
					)
				)
				(polyline
					(pts
						(xy 33.02 -6.35) (xy 33.02 -41.91)
					)
					(stroke
						(width 0.254)
						(type solid)
					)
					(fill
						(type background)
					)
				)
				(text "MDIO"
					(at 22.86 -33.02 900)
					(effects
						(font
							(size 1.27 1.27)
							(thickness 0.15)
						)
						(justify left bottom)
					)
				)
				(text "RST"
					(at 22.86 -58.928 900)
					(effects
						(font
							(size 1.27 1.27)
							(thickness 0.15)
						)
						(justify left bottom)
					)
				)
				(text "JTAG"
					(at 22.86 -72.39 900)
					(effects
						(font
							(size 1.27 1.27)
							(thickness 0.15)
						)
						(justify left bottom)
					)
				)
				(text "XTAL IN"
					(at 25.4 -7.366 900)
					(effects
						(font
							(size 1.27 1.27)
							(thickness 0.15)
						)
						(justify left bottom)
					)
				)
				(text "XTAL PTP"
					(at 25.4 -18.288 900)
					(effects
						(font
							(size 1.27 1.27)
							(thickness 0.15)
						)
						(justify left bottom)
					)
				)
				(text "SYNCE / IEEE1588"
					(at 31.75 -34.29 900)
					(effects
						(font
							(size 1.27 1.27)
							(thickness 0.15)
						)
						(justify left bottom)
					)
				)
				(pin input line
					(at 0 0 0)
					(length 5.08)
					(name "XTAL_P"
						(effects
							(font
								(size 1.27 1.27)
							)
						)
					)
					(number "D42"
						(effects
							(font
								(size 1.27 1.27)
							)
						)
					)
				)
				(pin input line
					(at 0 -2.54 0)
					(length 5.08)
					(name "XTAL_N"
						(effects
							(font
								(size 1.27 1.27)
							)
						)
					)
					(number "E41"
						(effects
							(font
								(size 1.27 1.27)
							)
						)
					)
				)
				(pin passive line
					(at 0 -5.08 0)
					(length 5.08)
					(name "XTAL_BYPASS"
						(effects
							(font
								(size 1.27 1.27)
							)
						)
					)
					(number "D10"
						(effects
							(font
								(size 1.27 1.27)
							)
						)
					)
				)
				(pin input line
					(at 0 -7.62 0)
					(length 5.08)
					(name "REFCLK_SEL"
						(effects
							(font
								(size 1.27 1.27)
							)
						)
					)
					(number "D4"
						(effects
							(font
								(size 1.27 1.27)
							)
						)
					)
				)
				(pin passive line
					(at 0 -12.7 0)
					(length 5.08)
					(name "XTAL_PTP_XTAL_P"
						(effects
							(font
								(size 1.27 1.27)
							)
						)
					)
					(number "J41"
						(effects
							(font
								(size 1.27 1.27)
							)
						)
					)
				)
				(pin passive line
					(at 0 -15.24 0)
					(length 5.08)
					(name "XTAL_PTP_XTAL_N"
						(effects
							(font
								(size 1.27 1.27)
							)
						)
					)
					(number "H42"
						(effects
							(font
								(size 1.27 1.27)
							)
						)
					)
				)
				(pin passive line
					(at 0 -20.32 0)
					(length 5.08)
					(name "RSVDK30_NC"
						(effects
							(font
								(size 1.27 1.27)
							)
						)
					)
					(number "K30"
						(effects
							(font
								(size 1.27 1.27)
							)
						)
					)
				)
				(pin passive line
					(at 0 -22.86 0)
					(length 5.08)
					(name "RSVDK32_NC"
						(effects
							(font
								(size 1.27 1.27)
							)
						)
					)
					(number "K32"
						(effects
							(font
								(size 1.27 1.27)
							)
						)
					)
				)
				(pin input line
					(at 0 -27.94 0)
					(length 5.08)
					(name "MDC"
						(effects
							(font
								(size 1.27 1.27)
							)
						)
					)
					(number "L41"
						(effects
							(font
								(size 1.27 1.27)
							)
						)
					)
				)
				(pin bidirectional line
					(at 0 -30.48 0)
					(length 5.08)
					(name "MDIO"
						(effects
							(font
								(size 1.27 1.27)
							)
						)
					)
					(number "M42"
						(effects
							(font
								(size 1.27 1.27)
							)
						)
					)
				)
				(pin passive line
					(at 0 -33.02 0)
					(length 5.08)
					(name "RSVDL33"
						(effects
							(font
								(size 1.27 1.27)
							)
						)
					)
					(number "L33"
						(effects
							(font
								(size 1.27 1.27)
							)
						)
					)
				)
				(pin passive line
					(at 0 -38.1 0)
					(length 5.08)
					(name "RSVDR33_NC"
						(effects
							(font
								(size 1.27 1.27)
							)
						)
					)
					(number "R33"
						(effects
							(font
								(size 1.27 1.27)
							)
						)
					)
				)
				(pin passive line
					(at 0 -40.64 0)
					(length 5.08)
					(name "RSVDM34_NC"
						(effects
							(font
								(size 1.27 1.27)
							)
						)
					)
					(number "M34"
						(effects
							(font
								(size 1.27 1.27)
							)
						)
					)
				)
				(pin passive line
					(at 0 -43.18 0)
					(length 5.08)
					(name "RSVDP34_NC"
						(effects
							(font
								(size 1.27 1.27)
							)
						)
					)
					(number "P34"
						(effects
							(font
								(size 1.27 1.27)
							)
						)
					)
				)
				(pin passive line
					(at 0 -45.72 0)
					(length 5.08)
					(name "RSVDN33_NC"
						(effects
							(font
								(size 1.27 1.27)
							)
						)
					)
					(number "N33"
						(effects
							(font
								(size 1.27 1.27)
							)
						)
					)
				)
				(pin passive line
					(at 0 -48.26 0)
					(length 5.08)
					(name "RSVDJ17_VSS"
						(effects
							(font
								(size 1.27 1.27)
							)
						)
					)
					(number "J17"
						(effects
							(font
								(size 1.27 1.27)
							)
						)
					)
					(alternate "RSVD" passive line)
					(alternate "VSS" power_in line)
				)
				(pin passive line
					(at 0 -50.8 0)
					(length 5.08)
					(name "RSVD_J11_VSS"
						(effects
							(font
								(size 1.27 1.27)
							)
						)
					)
					(number "J11"
						(effects
							(font
								(size 1.27 1.27)
							)
						)
					)
					(alternate "RSVD" passive line)
					(alternate "VSS" power_in line)
				)
				(pin input line
					(at 0 -55.88 0)
					(length 5.08)
					(name "~{RESET}"
						(effects
							(font
								(size 1.27 1.27)
							)
						)
					)
					(number "D12"
						(effects
							(font
								(size 1.27 1.27)
							)
						)
					)
				)
				(pin passive line
					(at 0 -58.42 0)
					(length 5.08)
					(name "RSVDJ13_VSS"
						(effects
							(font
								(size 1.27 1.27)
							)
						)
					)
					(number "J13"
						(effects
							(font
								(size 1.27 1.27)
							)
						)
					)
					(alternate "RSVD" passive line)
					(alternate "VSS" power_in line)
				)
				(pin input line
					(at 0 -63.5 0)
					(length 5.08)
					(name "~{PHY_TRST}"
						(effects
							(font
								(size 1.27 1.27)
							)
						)
					)
					(number "D18"
						(effects
							(font
								(size 1.27 1.27)
							)
						)
					)
				)
				(pin input line
					(at 0 -66.04 0)
					(length 5.08)
					(name "PHY_TCK"
						(effects
							(font
								(size 1.27 1.27)
							)
						)
					)
					(number "E17"
						(effects
							(font
								(size 1.27 1.27)
							)
						)
					)
				)
				(pin input line
					(at 0 -68.58 0)
					(length 5.08)
					(name "PHY_TMS"
						(effects
							(font
								(size 1.27 1.27)
							)
						)
					)
					(number "D16"
						(effects
							(font
								(size 1.27 1.27)
							)
						)
					)
				)
				(pin input line
					(at 0 -71.12 0)
					(length 5.08)
					(name "PHY_TDI"
						(effects
							(font
								(size 1.27 1.27)
							)
						)
					)
					(number "E15"
						(effects
							(font
								(size 1.27 1.27)
							)
						)
					)
				)
				(pin open_collector line
					(at 0 -73.66 0)
					(length 5.08)
					(name "PHY_TDO"
						(effects
							(font
								(size 1.27 1.27)
							)
						)
					)
					(number "F16"
						(effects
							(font
								(size 1.27 1.27)
							)
						)
					)
				)
				(pin input line
					(at 0 -76.2 0)
					(length 5.08)
					(name "RSVDD14"
						(effects
							(font
								(size 1.27 1.27)
							)
						)
					)
					(number "D14"
						(effects
							(font
								(size 1.27 1.27)
							)
						)
					)
				)
				(pin passive line
					(at 55.88 0 180)
					(length 5.08)
					(name "P0_INT_MLC"
						(effects
							(font
								(size 1.27 1.27)
							)
						)
					)
					(number "M40"
						(effects
							(font
								(size 1.27 1.27)
							)
						)
					)
				)
				(pin passive line
					(at 55.88 -2.54 180)
					(length 5.08)
					(name "P1_INT_MLC"
						(effects
							(font
								(size 1.27 1.27)
							)
						)
					)
					(number "F14"
						(effects
							(font
								(size 1.27 1.27)
							)
						)
					)
				)
				(pin passive line
					(at 55.88 -7.62 180)
					(length 5.08)
					(name "P0_PTP_SYNC0"
						(effects
							(font
								(size 1.27 1.27)
							)
						)
					)
					(number "N39"
						(effects
							(font
								(size 1.27 1.27)
							)
						)
					)
				)
				(pin passive line
					(at 55.88 -10.16 180)
					(length 5.08)
					(name "P0_PTP_SYNC1"
						(effects
							(font
								(size 1.27 1.27)
							)
						)
					)
					(number "N41"
						(effects
							(font
								(size 1.27 1.27)
							)
						)
					)
				)
				(pin passive line
					(at 55.88 -12.7 180)
					(length 5.08)
					(name "P1_PTP_SYNC0"
						(effects
							(font
								(size 1.27 1.27)
							)
						)
					)
					(number "H10"
						(effects
							(font
								(size 1.27 1.27)
							)
						)
					)
				)
				(pin passive line
					(at 55.88 -15.24 180)
					(length 5.08)
					(name "P1_PTP_SYNC1"
						(effects
							(font
								(size 1.27 1.27)
							)
						)
					)
					(number "H12"
						(effects
							(font
								(size 1.27 1.27)
							)
						)
					)
				)
				(pin output line
					(at 55.88 -20.32 180)
					(length 5.08)
					(name "SYNCE_CLKOUT_0"
						(effects
							(font
								(size 1.27 1.27)
							)
						)
					)
					(number "G9"
						(effects
							(font
								(size 1.27 1.27)
							)
						)
					)
				)
				(pin output line
					(at 55.88 -22.86 180)
					(length 5.08)
					(name "SYNCE_CLKOUT_1"
						(effects
							(font
								(size 1.27 1.27)
							)
						)
					)
					(number "F10"
						(effects
							(font
								(size 1.27 1.27)
							)
						)
					)
				)
				(pin output line
					(at 55.88 -25.4 180)
					(length 5.08)
					(name "SYNCE_CLKOUT_2"
						(effects
							(font
								(size 1.27 1.27)
							)
						)
					)
					(number "G11"
						(effects
							(font
								(size 1.27 1.27)
							)
						)
					)
				)
				(pin output line
					(at 55.88 -27.94 180)
					(length 5.08)
					(name "SYNCE_CLKOUT_3"
						(effects
							(font
								(size 1.27 1.27)
							)
						)
					)
					(number "E13"
						(effects
							(font
								(size 1.27 1.27)
							)
						)
					)
				)
				(pin output line
					(at 55.88 -33.02 180)
					(length 5.08)
					(name "SYNCE_LOCK_0"
						(effects
							(font
								(size 1.27 1.27)
							)
						)
					)
					(number "F8"
						(effects
							(font
								(size 1.27 1.27)
							)
						)
					)
				)
				(pin output line
					(at 55.88 -35.56 180)
					(length 5.08)
					(name "SYNCE_LOCK_1"
						(effects
							(font
								(size 1.27 1.27)
							)
						)
					)
					(number "E9"
						(effects
							(font
								(size 1.27 1.27)
							)
						)
					)
				)
				(pin output line
					(at 55.88 -38.1 180)
					(length 5.08)
					(name "SYNCE_LOCK_2"
						(effects
							(font
								(size 1.27 1.27)
							)
						)
					)
					(number "E11"
						(effects
							(font
								(size 1.27 1.27)
							)
						)
					)
				)
				(pin output line
					(at 55.88 -40.64 180)
					(length 5.08)
					(name "SYNCE_LOCK_3"
						(effects
							(font
								(size 1.27 1.27)
							)
						)
					)
					(number "F12"
						(effects
							(font
								(size 1.27 1.27)
							)
						)
					)
				)
				(pin passive line
					(at 55.88 -45.72 180)
					(length 5.08)
					(name "RSVDH40_VSS"
						(effects
							(font
								(size 1.27 1.27)
							)
						)
					)
					(number "H40"
						(effects
							(font
								(size 1.27 1.27)
							)
						)
					)
					(alternate "RSVD" passive line)
					(alternate "VSS" power_in line)
				)
				(pin passive line
					(at 55.88 -48.26 180)
					(length 5.08)
					(name "RSVDK40_1P88V"
						(effects
							(font
								(size 1.27 1.27)
							)
						)
					)
					(number "K40"
						(effects
							(font
								(size 1.27 1.27)
							)
						)
					)
					(alternate "1V88" power_in line)
					(alternate "RSVD" passive line)
				)
				(pin passive line
					(at 55.88 -50.8 180)
					(length 5.08)
					(name "RSVDK42_VSS"
						(effects
							(font
								(size 1.27 1.27)
							)
						)
					)
					(number "K42"
						(effects
							(font
								(size 1.27 1.27)
							)
						)
					)
					(alternate "RSVD" passive line)
					(alternate "VSS" power_in line)
				)
				(pin passive line
					(at 55.88 -53.34 180)
					(length 5.08)
					(name "RSVDP38_VSS"
						(effects
							(font
								(size 1.27 1.27)
							)
						)
					)
					(number "P38"
						(effects
							(font
								(size 1.27 1.27)
							)
						)
					)
					(alternate "RSVD" passive line)
					(alternate "VSS" power_in line)
				)
				(pin passive line
					(at 55.88 -55.88 180)
					(length 5.08)
					(name "RSVDN37_VSS"
						(effects
							(font
								(size 1.27 1.27)
							)
						)
					)
					(number "N37"
						(effects
							(font
								(size 1.27 1.27)
							)
						)
					)
					(alternate "RSVD" passive line)
					(alternate "VSS" power_in line)
				)
				(pin passive line
					(at 55.88 -58.42 180)
					(length 5.08)
					(name "RSVDL37_VSS"
						(effects
							(font
								(size 1.27 1.27)
							)
						)
					)
					(number "L37"
						(effects
							(font
								(size 1.27 1.27)
							)
						)
					)
					(alternate "RSVD" passive line)
					(alternate "VSS" power_in line)
				)
				(pin passive line
					(at 55.88 -63.5 180)
					(length 5.08)
					(name "RSVDL35_NC"
						(effects
							(font
								(size 1.27 1.27)
							)
						)
					)
					(number "L35"
						(effects
							(font
								(size 1.27 1.27)
							)
						)
					)
				)
				(pin passive line
					(at 55.88 -66.04 180)
					(length 5.08)
					(name "RSVDM36_NC"
						(effects
							(font
								(size 1.27 1.27)
							)
						)
					)
					(number "M36"
						(effects
							(font
								(size 1.27 1.27)
							)
						)
					)
				)
				(pin passive line
					(at 55.88 -68.58 180)
					(length 5.08)
					(name "RSVDN35_NC"
						(effects
							(font
								(size 1.27 1.27)
							)
						)
					)
					(number "N35"
						(effects
							(font
								(size 1.27 1.27)
							)
						)
					)
				)
				(pin passive line
					(at 55.88 -71.12 180)
					(length 5.08)
					(name "RSVDP36_NC"
						(effects
							(font
								(size 1.27 1.27)
							)
						)
					)
					(number "P36"
						(effects
							(font
								(size 1.27 1.27)
							)
						)
					)
				)
				(pin passive line
					(at 55.88 -73.66 180)
					(length 5.08)
					(name "RSVDR37_NC"
						(effects
							(font
								(size 1.27 1.27)
							)
						)
					)
					(number "R37"
						(effects
							(font
								(size 1.27 1.27)
							)
						)
					)
				)
				(pin passive line
					(at 55.88 -76.2 180)
					(length 5.08)
					(name "RSVDH16_NC"
						(effects
							(font
								(size 1.27 1.27)
							)
						)
					)
					(number "H16"
						(effects
							(font
								(size 1.27 1.27)
							)
						)
					)
				)
				(pin passive line
					(at 55.88 -78.74 180)
					(length 5.08)
					(name "RSVDG15_NC"
						(effects
							(font
								(size 1.27 1.27)
							)
						)
					)
					(number "G15"
						(effects
							(font
								(size 1.27 1.27)
							)
						)
					)
				)
				(pin passive line
					(at 55.88 -81.28 180)
					(length 5.08)
					(name "RSVDJ15_NC"
						(effects
							(font
								(size 1.27 1.27)
							)
						)
					)
					(number "J15"
						(effects
							(font
								(size 1.27 1.27)
							)
						)
					)
				)
				(pin passive line
					(at 55.88 -83.82 180)
					(length 5.08)
					(name "RSVDH14_NC"
						(effects
							(font
								(size 1.27 1.27)
							)
						)
					)
					(number "H14"
						(effects
							(font
								(size 1.27 1.27)
							)
						)
					)
				)
				(pin passive line
					(at 55.88 -86.36 180)
					(length 5.08)
					(name "RSVDG13_NC"
						(effects
							(font
								(size 1.27 1.27)
							)
						)
					)
					(number "G13"
						(effects
							(font
								(size 1.27 1.27)
							)
						)
					)
				)
			)
			(symbol "EZX710AT2_S_LMR5_7_1"
				(rectangle
					(start 5.08 2.54)
					(end 38.1 -71.12)
					(stroke
						(width 0.254)
						(type default)
					)
					(fill
						(type background)
					)
				)
				(pin passive line
					(at 0 0 0)
					(length 5.08)
					(name "RSVDE19_1P88V"
						(effects
							(font
								(size 1.27 1.27)
							)
						)
					)
					(number "E19"
						(effects
							(font
								(size 1.27 1.27)
							)
						)
					)
					(alternate "1V88" power_in line)
					(alternate "RSVD" passive line)
				)
				(pin passive line
					(at 0 -2.54 0)
					(length 5.08)
					(name "RSVDD8_1P88V"
						(effects
							(font
								(size 1.27 1.27)
							)
						)
					)
					(number "D8"
						(effects
							(font
								(size 1.27 1.27)
							)
						)
					)
					(alternate "1V88" power_in line)
					(alternate "RSVD" passive line)
				)
				(pin passive line
					(at 0 -5.08 0)
					(length 5.08)
					(name "RSVDJ19_VSS"
						(effects
							(font
								(size 1.27 1.27)
							)
						)
					)
					(number "J19"
						(effects
							(font
								(size 1.27 1.27)
							)
						)
					)
					(alternate "RSVD" passive line)
					(alternate "VSS" power_in line)
				)
				(pin passive line
					(at 0 -7.62 0)
					(length 5.08)
					(name "RSVDJ21_VSS"
						(effects
							(font
								(size 1.27 1.27)
							)
						)
					)
					(number "J21"
						(effects
							(font
								(size 1.27 1.27)
							)
						)
					)
					(alternate "RSVD" passive line)
					(alternate "VSS" power_in line)
				)
				(pin passive line
					(at 0 -10.16 0)
					(length 5.08)
					(name "RSVH18_VSS"
						(effects
							(font
								(size 1.27 1.27)
							)
						)
					)
					(number "H18"
						(effects
							(font
								(size 1.27 1.27)
							)
						)
					)
					(alternate "RSVD" passive line)
					(alternate "VSS" power_in line)
				)
				(pin passive line
					(at 0 -12.7 0)
					(length 5.08)
					(name "RSVDH22_VSS"
						(effects
							(font
								(size 1.27 1.27)
							)
						)
					)
					(number "H22"
						(effects
							(font
								(size 1.27 1.27)
							)
						)
					)
					(alternate "RSVD" passive line)
					(alternate "VSS" power_in line)
				)
				(pin passive line
					(at 0 -15.24 0)
					(length 5.08)
					(name "RSVDG19_VSS"
						(effects
							(font
								(size 1.27 1.27)
							)
						)
					)
					(number "G19"
						(effects
							(font
								(size 1.27 1.27)
							)
						)
					)
					(alternate "RSVD" passive line)
					(alternate "VSS" power_in line)
				)
				(pin passive line
					(at 0 -17.78 0)
					(length 5.08)
					(name "RSVDG21_VSS"
						(effects
							(font
								(size 1.27 1.27)
							)
						)
					)
					(number "G21"
						(effects
							(font
								(size 1.27 1.27)
							)
						)
					)
					(alternate "RSVD" passive line)
					(alternate "VSS" power_in line)
				)
				(pin passive line
					(at 0 -20.32 0)
					(length 5.08)
					(name "RSVDF18_VSS"
						(effects
							(font
								(size 1.27 1.27)
							)
						)
					)
					(number "F18"
						(effects
							(font
								(size 1.27 1.27)
							)
						)
					)
					(alternate "RSVD" passive line)
					(alternate "VSS" power_in line)
				)
				(pin passive line
					(at 0 -22.86 0)
					(length 5.08)
					(name "RSVDF20_VSS"
						(effects
							(font
								(size 1.27 1.27)
							)
						)
					)
					(number "F20"
						(effects
							(font
								(size 1.27 1.27)
							)
						)
					)
					(alternate "RSVD" passive line)
					(alternate "VSS" power_in line)
				)
				(pin passive line
					(at 0 -25.4 0)
					(length 5.08)
					(name "RSVDF22_VSS"
						(effects
							(font
								(size 1.27 1.27)
							)
						)
					)
					(number "F22"
						(effects
							(font
								(size 1.27 1.27)
							)
						)
					)
					(alternate "RSVD" passive line)
					(alternate "VSS" power_in line)
				)
				(pin passive line
					(at 0 -27.94 0)
					(length 5.08)
					(name "RSVDE21_VSS"
						(effects
							(font
								(size 1.27 1.27)
							)
						)
					)
					(number "E21"
						(effects
							(font
								(size 1.27 1.27)
							)
						)
					)
					(alternate "RSVD" passive line)
					(alternate "VSS" power_in line)
				)
				(pin passive line
					(at 0 -30.48 0)
					(length 5.08)
					(name "RSVDE23_VSS"
						(effects
							(font
								(size 1.27 1.27)
							)
						)
					)
					(number "E23"
						(effects
							(font
								(size 1.27 1.27)
							)
						)
					)
					(alternate "RSVD" passive line)
					(alternate "VSS" power_in line)
				)
				(pin passive line
					(at 0 -33.02 0)
					(length 5.08)
					(name "RSVDE25_VSS"
						(effects
							(font
								(size 1.27 1.27)
							)
						)
					)
					(number "E25"
						(effects
							(font
								(size 1.27 1.27)
							)
						)
					)
					(alternate "RSVD" passive line)
					(alternate "VSS" power_in line)
				)
				(pin passive line
					(at 0 -35.56 0)
					(length 5.08)
					(name "RSVDD22_VSS"
						(effects
							(font
								(size 1.27 1.27)
							)
						)
					)
					(number "D22"
						(effects
							(font
								(size 1.27 1.27)
							)
						)
					)
					(alternate "RSVD" passive line)
					(alternate "VSS" power_in line)
				)
				(pin passive line
					(at 0 -38.1 0)
					(length 5.08)
					(name "RSVDG23_VSS"
						(effects
							(font
								(size 1.27 1.27)
							)
						)
					)
					(number "G23"
						(effects
							(font
								(size 1.27 1.27)
							)
						)
					)
					(alternate "RSVD" passive line)
					(alternate "VSS" power_in line)
				)
				(pin passive line
					(at 0 -40.64 0)
					(length 5.08)
					(name "RSVDH24_VSS"
						(effects
							(font
								(size 1.27 1.27)
							)
						)
					)
					(number "H24"
						(effects
							(font
								(size 1.27 1.27)
							)
						)
					)
					(alternate "RSVD" passive line)
					(alternate "VSS" power_in line)
				)
				(pin passive line
					(at 0 -45.72 0)
					(length 5.08)
					(name "RSVDK34_NC"
						(effects
							(font
								(size 1.27 1.27)
							)
						)
					)
					(number "K34"
						(effects
							(font
								(size 1.27 1.27)
							)
						)
					)
				)
				(pin passive line
					(at 0 -48.26 0)
					(length 5.08)
					(name "RSVDK36_NC"
						(effects
							(font
								(size 1.27 1.27)
							)
						)
					)
					(number "K36"
						(effects
							(font
								(size 1.27 1.27)
							)
						)
					)
				)
				(pin passive line
					(at 0 -50.8 0)
					(length 5.08)
					(name "RSVDK26_NC"
						(effects
							(font
								(size 1.27 1.27)
							)
						)
					)
					(number "K26"
						(effects
							(font
								(size 1.27 1.27)
							)
						)
					)
				)
				(pin passive line
					(at 0 -53.34 0)
					(length 5.08)
					(name "RSVDK28_NC"
						(effects
							(font
								(size 1.27 1.27)
							)
						)
					)
					(number "K28"
						(effects
							(font
								(size 1.27 1.27)
							)
						)
					)
				)
				(pin passive line
					(at 0 -58.42 0)
					(length 5.08)
					(name "RSVDD20_NC"
						(effects
							(font
								(size 1.27 1.27)
							)
						)
					)
					(number "D20"
						(effects
							(font
								(size 1.27 1.27)
							)
						)
					)
				)
				(pin passive line
					(at 0 -60.96 0)
					(length 5.08)
					(name "RSVDC21_NC"
						(effects
							(font
								(size 1.27 1.27)
							)
						)
					)
					(number "C21"
						(effects
							(font
								(size 1.27 1.27)
							)
						)
					)
				)
				(pin passive line
					(at 0 -66.04 0)
					(length 5.08)
					(name "RSVDB42_NC"
						(effects
							(font
								(size 1.27 1.27)
							)
						)
					)
					(number "B42"
						(effects
							(font
								(size 1.27 1.27)
							)
						)
					)
				)
				(pin passive line
					(at 0 -68.58 0)
					(length 5.08)
					(name "RSVDA41_NC"
						(effects
							(font
								(size 1.27 1.27)
							)
						)
					)
					(number "A41"
						(effects
							(font
								(size 1.27 1.27)
							)
						)
					)
				)
				(pin passive line
					(at 43.18 0 180)
					(length 5.08)
					(name "RSVDL29_NC"
						(effects
							(font
								(size 1.27 1.27)
							)
						)
					)
					(number "L29"
						(effects
							(font
								(size 1.27 1.27)
							)
						)
					)
				)
				(pin passive line
					(at 43.18 -2.54 180)
					(length 5.08)
					(name "RSVDM32_NC"
						(effects
							(font
								(size 1.27 1.27)
							)
						)
					)
					(number "M32"
						(effects
							(font
								(size 1.27 1.27)
							)
						)
					)
				)
				(pin passive line
					(at 43.18 -5.08 180)
					(length 5.08)
					(name "RSVDM30_NC"
						(effects
							(font
								(size 1.27 1.27)
							)
						)
					)
					(number "M30"
						(effects
							(font
								(size 1.27 1.27)
							)
						)
					)
				)
				(pin passive line
					(at 43.18 -7.62 180)
					(length 5.08)
					(name "RSVDN31_NC"
						(effects
							(font
								(size 1.27 1.27)
							)
						)
					)
					(number "N31"
						(effects
							(font
								(size 1.27 1.27)
							)
						)
					)
				)
				(pin passive line
					(at 43.18 -10.16 180)
					(length 5.08)
					(name "RSVDN29_NC"
						(effects
							(font
								(size 1.27 1.27)
							)
						)
					)
					(number "N29"
						(effects
							(font
								(size 1.27 1.27)
							)
						)
					)
				)
				(pin passive line
					(at 43.18 -12.7 180)
					(length 5.08)
					(name "RSVDP32_NC"
						(effects
							(font
								(size 1.27 1.27)
							)
						)
					)
					(number "P32"
						(effects
							(font
								(size 1.27 1.27)
							)
						)
					)
				)
				(pin passive line
					(at 43.18 -15.24 180)
					(length 5.08)
					(name "RSVDP30_NC"
						(effects
							(font
								(size 1.27 1.27)
							)
						)
					)
					(number "P30"
						(effects
							(font
								(size 1.27 1.27)
							)
						)
					)
				)
				(pin passive line
					(at 43.18 -17.78 180)
					(length 5.08)
					(name "RSVDR31_NC"
						(effects
							(font
								(size 1.27 1.27)
							)
						)
					)
					(number "R31"
						(effects
							(font
								(size 1.27 1.27)
							)
						)
					)
				)
				(pin passive line
					(at 43.18 -20.32 180)
					(length 5.08)
					(name "RSVDR29_NC"
						(effects
							(font
								(size 1.27 1.27)
							)
						)
					)
					(number "R29"
						(effects
							(font
								(size 1.27 1.27)
							)
						)
					)
				)
				(pin passive line
					(at 43.18 -22.86 180)
					(length 5.08)
					(name "RSVDT32_NC"
						(effects
							(font
								(size 1.27 1.27)
							)
						)
					)
					(number "T32"
						(effects
							(font
								(size 1.27 1.27)
							)
						)
					)
				)
				(pin passive line
					(at 43.18 -25.4 180)
					(length 5.08)
					(name "RSVDT30_NC"
						(effects
							(font
								(size 1.27 1.27)
							)
						)
					)
					(number "T30"
						(effects
							(font
								(size 1.27 1.27)
							)
						)
					)
				)
				(pin passive line
					(at 43.18 -27.94 180)
					(length 5.08)
					(name "RSVDU35_NC"
						(effects
							(font
								(size 1.27 1.27)
							)
						)
					)
					(number "U35"
						(effects
							(font
								(size 1.27 1.27)
							)
						)
					)
				)
				(pin passive line
					(at 43.18 -30.48 180)
					(length 5.08)
					(name "RSVDU33_NC"
						(effects
							(font
								(size 1.27 1.27)
							)
						)
					)
					(number "U33"
						(effects
							(font
								(size 1.27 1.27)
							)
						)
					)
				)
				(pin passive line
					(at 43.18 -33.02 180)
					(length 5.08)
					(name "RSVDU31_NC"
						(effects
							(font
								(size 1.27 1.27)
							)
						)
					)
					(number "U31"
						(effects
							(font
								(size 1.27 1.27)
							)
						)
					)
				)
				(pin passive line
					(at 43.18 -35.56 180)
					(length 5.08)
					(name "RSVDV34_NC"
						(effects
							(font
								(size 1.27 1.27)
							)
						)
					)
					(number "V34"
						(effects
							(font
								(size 1.27 1.27)
							)
						)
					)
				)
				(pin passive line
					(at 43.18 -38.1 180)
					(length 5.08)
					(name "RSVDV32_NC"
						(effects
							(font
								(size 1.27 1.27)
							)
						)
					)
					(number "V32"
						(effects
							(font
								(size 1.27 1.27)
							)
						)
					)
				)
				(pin passive line
					(at 43.18 -40.64 180)
					(length 5.08)
					(name "RSVDV30_NC"
						(effects
							(font
								(size 1.27 1.27)
							)
						)
					)
					(number "V30"
						(effects
							(font
								(size 1.27 1.27)
							)
						)
					)
				)
				(pin passive line
					(at 43.18 -45.72 180)
					(length 5.08)
					(name "RSVDL31_VSS"
						(effects
							(font
								(size 1.27 1.27)
							)
						)
					)
					(number "L31"
						(effects
							(font
								(size 1.27 1.27)
							)
						)
					)
					(alternate "RSVD" passive line)
					(alternate "VSS" power_in line)
				)
				(pin passive line
					(at 43.18 -50.8 180)
					(length 5.08)
					(name "RSVDD6_VSS"
						(effects
							(font
								(size 1.27 1.27)
							)
						)
					)
					(number "D6"
						(effects
							(font
								(size 1.27 1.27)
							)
						)
					)
					(alternate "RSVD" passive line)
					(alternate "VSS" power_in line)
				)
				(pin passive line
					(at 43.18 -53.34 180)
					(length 5.08)
					(name "RSVDF38_VSS"
						(effects
							(font
								(size 1.27 1.27)
							)
						)
					)
					(number "F38"
						(effects
							(font
								(size 1.27 1.27)
							)
						)
					)
					(alternate "RSVD" passive line)
					(alternate "VSS" power_in line)
				)
				(pin passive line
					(at 43.18 -55.88 180)
					(length 5.08)
					(name "RSVDD32_NC"
						(effects
							(font
								(size 1.27 1.27)
							)
						)
					)
					(number "D32"
						(effects
							(font
								(size 1.27 1.27)
							)
						)
					)
				)
				(pin passive line
					(at 43.18 -58.42 180)
					(length 5.08)
					(name "RSVDJ39_NC"
						(effects
							(font
								(size 1.27 1.27)
							)
						)
					)
					(number "J39"
						(effects
							(font
								(size 1.27 1.27)
							)
						)
					)
				)
			)
			(symbol "EZX710AT2_S_LMR5_8_1"
				(rectangle
					(start 5.08 2.54)
					(end 45.72 -55.88)
					(stroke
						(width 0.254)
						(type default)
					)
					(fill
						(type background)
					)
				)
				(polyline
					(pts
						(xy 31.75 -39.37) (xy 31.75 -54.61)
					)
					(stroke
						(width 0.254)
						(type solid)
					)
					(fill
						(type background)
					)
				)
				(text "Power supply"
					(at 19.05 -1.27 0)
					(effects
						(font
							(size 1.27 1.27)
							(thickness 0.15)
						)
						(justify left bottom)
					)
				)
				(text "GND"
					(at 30.48 -49.53 900)
					(effects
						(font
							(size 1.27 1.27)
							(thickness 0.15)
						)
						(justify left bottom)
					)
				)
				(pin power_in line
					(at 0 0 0)
					(length 5.08)
					(name "DVDD"
						(effects
							(font
								(size 1.27 1.27)
							)
						)
					)
					(number "G27"
						(effects
							(font
								(size 1.27 1.27)
							)
						)
					)
				)
				(pin passive line
					(at 0 0 0)
					(length 5.08)
					(hide yes)
					(name "DVDD"
						(effects
							(font
								(size 1.27 1.27)
							)
						)
					)
					(number "G29"
						(effects
							(font
								(size 1.27 1.27)
							)
						)
					)
				)
				(pin passive line
					(at 0 0 0)
					(length 5.08)
					(hide yes)
					(name "DVDD"
						(effects
							(font
								(size 1.27 1.27)
							)
						)
					)
					(number "G31"
						(effects
							(font
								(size 1.27 1.27)
							)
						)
					)
				)
				(pin passive line
					(at 0 0 0)
					(length 5.08)
					(hide yes)
					(name "DVDD"
						(effects
							(font
								(size 1.27 1.27)
							)
						)
					)
					(number "G33"
						(effects
							(font
								(size 1.27 1.27)
							)
						)
					)
				)
				(pin passive line
					(at 0 0 0)
					(length 5.08)
					(hide yes)
					(name "DVDD"
						(effects
							(font
								(size 1.27 1.27)
							)
						)
					)
					(number "G35"
						(effects
							(font
								(size 1.27 1.27)
							)
						)
					)
				)
				(pin power_in line
					(at 0 -5.08 0)
					(length 5.08)
					(name "VDDIO1"
						(effects
							(font
								(size 1.27 1.27)
							)
						)
					)
					(number "G25"
						(effects
							(font
								(size 1.27 1.27)
							)
						)
					)
				)
				(pin passive line
					(at 0 -5.08 0)
					(length 5.08)
					(hide yes)
					(name "VDDIO1"
						(effects
							(font
								(size 1.27 1.27)
							)
						)
					)
					(number "G37"
						(effects
							(font
								(size 1.27 1.27)
							)
						)
					)
				)
				(pin power_in line
					(at 0 -7.62 0)
					(length 5.08)
					(name "VDDIO2"
						(effects
							(font
								(size 1.27 1.27)
							)
						)
					)
					(number "L39"
						(effects
							(font
								(size 1.27 1.27)
							)
						)
					)
				)
				(pin power_in line
					(at 0 -10.16 0)
					(length 5.08)
					(name "VDDP2"
						(effects
							(font
								(size 1.27 1.27)
							)
						)
					)
					(number "M38"
						(effects
							(font
								(size 1.27 1.27)
							)
						)
					)
				)
				(pin power_in line
					(at 0 -15.24 0)
					(length 5.08)
					(name "XGB_AVDDH"
						(effects
							(font
								(size 1.27 1.27)
							)
						)
					)
					(number "D34"
						(effects
							(font
								(size 1.27 1.27)
							)
						)
					)
				)
				(pin power_in line
					(at 0 -20.32 0)
					(length 5.08)
					(name "BIAS_AVDDH"
						(effects
							(font
								(size 1.27 1.27)
							)
						)
					)
					(number "D30"
						(effects
							(font
								(size 1.27 1.27)
							)
						)
					)
				)
				(pin power_in line
					(at 0 -22.86 0)
					(length 5.08)
					(name "P0_AVDDH"
						(effects
							(font
								(size 1.27 1.27)
							)
						)
					)
					(number "E35"
						(effects
							(font
								(size 1.27 1.27)
							)
						)
					)
				)
				(pin passive line
					(at 0 -22.86 0)
					(length 5.08)
					(hide yes)
					(name "P0_AVDDH"
						(effects
							(font
								(size 1.27 1.27)
							)
						)
					)
					(number "E37"
						(effects
							(font
								(size 1.27 1.27)
							)
						)
					)
				)
				(pin power_in line
					(at 0 -25.4 0)
					(length 5.08)
					(name "P1_AVDDH"
						(effects
							(font
								(size 1.27 1.27)
							)
						)
					)
					(number "E27"
						(effects
							(font
								(size 1.27 1.27)
							)
						)
					)
				)
				(pin passive line
					(at 0 -25.4 0)
					(length 5.08)
					(hide yes)
					(name "P1_AVDDH"
						(effects
							(font
								(size 1.27 1.27)
							)
						)
					)
					(number "E29"
						(effects
							(font
								(size 1.27 1.27)
							)
						)
					)
				)
				(pin power_in line
					(at 0 -30.48 0)
					(length 5.08)
					(name "P0_AVDDL"
						(effects
							(font
								(size 1.27 1.27)
							)
						)
					)
					(number "C33"
						(effects
							(font
								(size 1.27 1.27)
							)
						)
					)
				)
				(pin passive line
					(at 0 -30.48 0)
					(length 5.08)
					(hide yes)
					(name "P0_AVDDL"
						(effects
							(font
								(size 1.27 1.27)
							)
						)
					)
					(number "C35"
						(effects
							(font
								(size 1.27 1.27)
							)
						)
					)
				)
				(pin passive line
					(at 0 -30.48 0)
					(length 5.08)
					(hide yes)
					(name "P0_AVDDL"
						(effects
							(font
								(size 1.27 1.27)
							)
						)
					)
					(number "C37"
						(effects
							(font
								(size 1.27 1.27)
							)
						)
					)
				)
				(pin passive line
					(at 0 -30.48 0)
					(length 5.08)
					(hide yes)
					(name "P0_AVDDL"
						(effects
							(font
								(size 1.27 1.27)
							)
						)
					)
					(number "C39"
						(effects
							(font
								(size 1.27 1.27)
							)
						)
					)
				)
				(pin power_in line
					(at 0 -35.56 0)
					(length 5.08)
					(name "P1_AVDDL"
						(effects
							(font
								(size 1.27 1.27)
							)
						)
					)
					(number "C23"
						(effects
							(font
								(size 1.27 1.27)
							)
						)
					)
				)
				(pin passive line
					(at 0 -35.56 0)
					(length 5.08)
					(hide yes)
					(name "P1_AVDDL"
						(effects
							(font
								(size 1.27 1.27)
							)
						)
					)
					(number "C25"
						(effects
							(font
								(size 1.27 1.27)
							)
						)
					)
				)
				(pin passive line
					(at 0 -35.56 0)
					(length 5.08)
					(hide yes)
					(name "P1_AVDDL"
						(effects
							(font
								(size 1.27 1.27)
							)
						)
					)
					(number "C27"
						(effects
							(font
								(size 1.27 1.27)
							)
						)
					)
				)
				(pin passive line
					(at 0 -35.56 0)
					(length 5.08)
					(hide yes)
					(name "P1_AVDDL"
						(effects
							(font
								(size 1.27 1.27)
							)
						)
					)
					(number "C29"
						(effects
							(font
								(size 1.27 1.27)
							)
						)
					)
				)
				(pin power_in line
					(at 0 -40.64 0)
					(length 5.08)
					(name "XFI_VDD"
						(effects
							(font
								(size 1.27 1.27)
							)
						)
					)
					(number "J27"
						(effects
							(font
								(size 1.27 1.27)
							)
						)
					)
				)
				(pin passive line
					(at 0 -40.64 0)
					(length 5.08)
					(hide yes)
					(name "XFI_VDD"
						(effects
							(font
								(size 1.27 1.27)
							)
						)
					)
					(number "J29"
						(effects
							(font
								(size 1.27 1.27)
							)
						)
					)
				)
				(pin passive line
					(at 0 -40.64 0)
					(length 5.08)
					(hide yes)
					(name "XFI_VDD"
						(effects
							(font
								(size 1.27 1.27)
							)
						)
					)
					(number "J31"
						(effects
							(font
								(size 1.27 1.27)
							)
						)
					)
				)
				(pin passive line
					(at 0 -40.64 0)
					(length 5.08)
					(hide yes)
					(name "XFI_VDD"
						(effects
							(font
								(size 1.27 1.27)
							)
						)
					)
					(number "J35"
						(effects
							(font
								(size 1.27 1.27)
							)
						)
					)
				)
				(pin power_in line
					(at 0 -45.72 0)
					(length 5.08)
					(name "XFI_PVDD"
						(effects
							(font
								(size 1.27 1.27)
							)
						)
					)
					(number "J33"
						(effects
							(font
								(size 1.27 1.27)
							)
						)
					)
				)
				(pin power_in line
					(at 0 -50.8 0)
					(length 5.08)
					(name "PLL_VDD"
						(effects
							(font
								(size 1.27 1.27)
							)
						)
					)
					(number "G39"
						(effects
							(font
								(size 1.27 1.27)
							)
						)
					)
				)
				(pin power_in line
					(at 50.8 0 180)
					(length 5.08)
					(name "VCCA"
						(effects
							(font
								(size 1.27 1.27)
							)
						)
					)
					(number "L11"
						(effects
							(font
								(size 1.27 1.27)
							)
						)
					)
				)
				(pin passive line
					(at 50.8 0 180)
					(length 5.08)
					(hide yes)
					(name "VCCA"
						(effects
							(font
								(size 1.27 1.27)
							)
						)
					)
					(number "L13"
						(effects
							(font
								(size 1.27 1.27)
							)
						)
					)
				)
				(pin passive line
					(at 50.8 0 180)
					(length 5.08)
					(hide yes)
					(name "VCCA"
						(effects
							(font
								(size 1.27 1.27)
							)
						)
					)
					(number "L15"
						(effects
							(font
								(size 1.27 1.27)
							)
						)
					)
				)
				(pin passive line
					(at 50.8 0 180)
					(length 5.08)
					(hide yes)
					(name "VCCA"
						(effects
							(font
								(size 1.27 1.27)
							)
						)
					)
					(number "L17"
						(effects
							(font
								(size 1.27 1.27)
							)
						)
					)
				)
				(pin passive line
					(at 50.8 0 180)
					(length 5.08)
					(hide yes)
					(name "VCCA"
						(effects
							(font
								(size 1.27 1.27)
							)
						)
					)
					(number "N11"
						(effects
							(font
								(size 1.27 1.27)
							)
						)
					)
				)
				(pin passive line
					(at 50.8 0 180)
					(length 5.08)
					(hide yes)
					(name "VCCA"
						(effects
							(font
								(size 1.27 1.27)
							)
						)
					)
					(number "N13"
						(effects
							(font
								(size 1.27 1.27)
							)
						)
					)
				)
				(pin passive line
					(at 50.8 0 180)
					(length 5.08)
					(hide yes)
					(name "VCCA"
						(effects
							(font
								(size 1.27 1.27)
							)
						)
					)
					(number "N15"
						(effects
							(font
								(size 1.27 1.27)
							)
						)
					)
				)
				(pin passive line
					(at 50.8 0 180)
					(length 5.08)
					(hide yes)
					(name "VCCA"
						(effects
							(font
								(size 1.27 1.27)
							)
						)
					)
					(number "W13"
						(effects
							(font
								(size 1.27 1.27)
							)
						)
					)
				)
				(pin passive line
					(at 50.8 0 180)
					(length 5.08)
					(hide yes)
					(name "VCCA"
						(effects
							(font
								(size 1.27 1.27)
							)
						)
					)
					(number "W15"
						(effects
							(font
								(size 1.27 1.27)
							)
						)
					)
				)
				(pin passive line
					(at 50.8 0 180)
					(length 5.08)
					(hide yes)
					(name "VCCA"
						(effects
							(font
								(size 1.27 1.27)
							)
						)
					)
					(number "W17"
						(effects
							(font
								(size 1.27 1.27)
							)
						)
					)
				)
				(pin passive line
					(at 50.8 0 180)
					(length 5.08)
					(hide yes)
					(name "VCCA"
						(effects
							(font
								(size 1.27 1.27)
							)
						)
					)
					(number "W19"
						(effects
							(font
								(size 1.27 1.27)
							)
						)
					)
				)
				(pin passive line
					(at 50.8 0 180)
					(length 5.08)
					(hide yes)
					(name "VCCA"
						(effects
							(font
								(size 1.27 1.27)
							)
						)
					)
					(number "W21"
						(effects
							(font
								(size 1.27 1.27)
							)
						)
					)
				)
				(pin power_in line
					(at 50.8 -5.08 180)
					(length 5.08)
					(name "VCCD"
						(effects
							(font
								(size 1.27 1.27)
							)
						)
					)
					(number "L19"
						(effects
							(font
								(size 1.27 1.27)
							)
						)
					)
				)
				(pin passive line
					(at 50.8 -5.08 180)
					(length 5.08)
					(hide yes)
					(name "VCCD"
						(effects
							(font
								(size 1.27 1.27)
							)
						)
					)
					(number "L21"
						(effects
							(font
								(size 1.27 1.27)
							)
						)
					)
				)
				(pin passive line
					(at 50.8 -5.08 180)
					(length 5.08)
					(hide yes)
					(name "VCCD"
						(effects
							(font
								(size 1.27 1.27)
							)
						)
					)
					(number "N17"
						(effects
							(font
								(size 1.27 1.27)
							)
						)
					)
				)
				(pin passive line
					(at 50.8 -5.08 180)
					(length 5.08)
					(hide yes)
					(name "VCCD"
						(effects
							(font
								(size 1.27 1.27)
							)
						)
					)
					(number "N19"
						(effects
							(font
								(size 1.27 1.27)
							)
						)
					)
				)
				(pin passive line
					(at 50.8 -5.08 180)
					(length 5.08)
					(hide yes)
					(name "VCCD"
						(effects
							(font
								(size 1.27 1.27)
							)
						)
					)
					(number "N21"
						(effects
							(font
								(size 1.27 1.27)
							)
						)
					)
				)
				(pin passive line
					(at 50.8 -5.08 180)
					(length 5.08)
					(hide yes)
					(name "VCCD"
						(effects
							(font
								(size 1.27 1.27)
							)
						)
					)
					(number "R13"
						(effects
							(font
								(size 1.27 1.27)
							)
						)
					)
				)
				(pin passive line
					(at 50.8 -5.08 180)
					(length 5.08)
					(hide yes)
					(name "VCCD"
						(effects
							(font
								(size 1.27 1.27)
							)
						)
					)
					(number "R15"
						(effects
							(font
								(size 1.27 1.27)
							)
						)
					)
				)
				(pin passive line
					(at 50.8 -5.08 180)
					(length 5.08)
					(hide yes)
					(name "VCCD"
						(effects
							(font
								(size 1.27 1.27)
							)
						)
					)
					(number "R17"
						(effects
							(font
								(size 1.27 1.27)
							)
						)
					)
				)
				(pin passive line
					(at 50.8 -5.08 180)
					(length 5.08)
					(hide yes)
					(name "VCCD"
						(effects
							(font
								(size 1.27 1.27)
							)
						)
					)
					(number "R19"
						(effects
							(font
								(size 1.27 1.27)
							)
						)
					)
				)
				(pin passive line
					(at 50.8 -5.08 180)
					(length 5.08)
					(hide yes)
					(name "VCCD"
						(effects
							(font
								(size 1.27 1.27)
							)
						)
					)
					(number "R21"
						(effects
							(font
								(size 1.27 1.27)
							)
						)
					)
				)
				(pin passive line
					(at 50.8 -5.08 180)
					(length 5.08)
					(hide yes)
					(name "VCCD"
						(effects
							(font
								(size 1.27 1.27)
							)
						)
					)
					(number "U11"
						(effects
							(font
								(size 1.27 1.27)
							)
						)
					)
				)
				(pin passive line
					(at 50.8 -5.08 180)
					(length 5.08)
					(hide yes)
					(name "VCCD"
						(effects
							(font
								(size 1.27 1.27)
							)
						)
					)
					(number "U13"
						(effects
							(font
								(size 1.27 1.27)
							)
						)
					)
				)
				(pin passive line
					(at 50.8 -5.08 180)
					(length 5.08)
					(hide yes)
					(name "VCCD"
						(effects
							(font
								(size 1.27 1.27)
							)
						)
					)
					(number "U15"
						(effects
							(font
								(size 1.27 1.27)
							)
						)
					)
				)
				(pin passive line
					(at 50.8 -5.08 180)
					(length 5.08)
					(hide yes)
					(name "VCCD"
						(effects
							(font
								(size 1.27 1.27)
							)
						)
					)
					(number "U17"
						(effects
							(font
								(size 1.27 1.27)
							)
						)
					)
				)
				(pin passive line
					(at 50.8 -5.08 180)
					(length 5.08)
					(hide yes)
					(name "VCCD"
						(effects
							(font
								(size 1.27 1.27)
							)
						)
					)
					(number "U19"
						(effects
							(font
								(size 1.27 1.27)
							)
						)
					)
				)
				(pin power_in line
					(at 50.8 -7.62 180)
					(length 5.08)
					(name "VCCD_A"
						(effects
							(font
								(size 1.27 1.27)
							)
						)
					)
					(number "W9"
						(effects
							(font
								(size 1.27 1.27)
							)
						)
					)
				)
				(pin passive line
					(at 50.8 -10.16 180)
					(length 5.08)
					(name "RSVDT8_VCCD"
						(effects
							(font
								(size 1.27 1.27)
							)
						)
					)
					(number "T8"
						(effects
							(font
								(size 1.27 1.27)
							)
						)
					)
				)
				(pin passive line
					(at 50.8 -15.24 180)
					(length 5.08)
					(hide yes)
					(name "VCC3P3"
						(effects
							(font
								(size 1.27 1.27)
							)
						)
					)
					(number "R11"
						(effects
							(font
								(size 1.27 1.27)
							)
						)
					)
				)
				(pin passive line
					(at 50.8 -15.24 180)
					(length 5.08)
					(hide yes)
					(name "VCC3P3"
						(effects
							(font
								(size 1.27 1.27)
							)
						)
					)
					(number "T34"
						(effects
							(font
								(size 1.27 1.27)
							)
						)
					)
				)
				(pin power_in line
					(at 50.8 -15.24 180)
					(length 5.08)
					(name "VCC3P3"
						(effects
							(font
								(size 1.27 1.27)
							)
						)
					)
					(number "U21"
						(effects
							(font
								(size 1.27 1.27)
							)
						)
					)
				)
				(pin power_in line
					(at 50.8 -17.78 180)
					(length 5.08)
					(name "VCC3P3_A"
						(effects
							(font
								(size 1.27 1.27)
							)
						)
					)
					(number "W11"
						(effects
							(font
								(size 1.27 1.27)
							)
						)
					)
				)
				(pin power_in line
					(at 50.8 -20.32 180)
					(length 5.08)
					(name "VCC3P3_TX"
						(effects
							(font
								(size 1.27 1.27)
							)
						)
					)
					(number "L9"
						(effects
							(font
								(size 1.27 1.27)
							)
						)
					)
				)
				(pin power_in line
					(at 50.8 -25.4 180)
					(length 5.08)
					(name "VCC3P3_SVR"
						(effects
							(font
								(size 1.27 1.27)
							)
						)
					)
					(number "T2"
						(effects
							(font
								(size 1.27 1.27)
							)
						)
					)
				)
				(pin passive line
					(at 50.8 -27.94 180)
					(length 5.08)
					(name "SVR_IND"
						(effects
							(font
								(size 1.27 1.27)
							)
						)
					)
					(number "V2"
						(effects
							(font
								(size 1.27 1.27)
							)
						)
					)
				)
				(pin passive line
					(at 50.8 -33.02 180)
					(length 5.08)
					(name "RSVDV8_NC"
						(effects
							(font
								(size 1.27 1.27)
							)
						)
					)
					(number "V8"
						(effects
							(font
								(size 1.27 1.27)
							)
						)
					)
				)
				(pin passive line
					(at 50.8 -35.56 180)
					(length 5.08)
					(name "RSVDV10_NC"
						(effects
							(font
								(size 1.27 1.27)
							)
						)
					)
					(number "V10"
						(effects
							(font
								(size 1.27 1.27)
							)
						)
					)
				)
				(pin passive line
					(at 50.8 -40.64 180)
					(length 5.08)
					(hide yes)
					(name "VSSA"
						(effects
							(font
								(size 1.27 1.27)
							)
						)
					)
					(number "A11"
						(effects
							(font
								(size 1.27 1.27)
							)
						)
					)
				)
				(pin passive line
					(at 50.8 -40.64 180)
					(length 5.08)
					(hide yes)
					(name "VSSA"
						(effects
							(font
								(size 1.27 1.27)
							)
						)
					)
					(number "A15"
						(effects
							(font
								(size 1.27 1.27)
							)
						)
					)
				)
				(pin passive line
					(at 50.8 -40.64 180)
					(length 5.08)
					(hide yes)
					(name "VSSA"
						(effects
							(font
								(size 1.27 1.27)
							)
						)
					)
					(number "A19"
						(effects
							(font
								(size 1.27 1.27)
							)
						)
					)
				)
				(pin power_in line
					(at 50.8 -40.64 180)
					(length 5.08)
					(name "VSSA"
						(effects
							(font
								(size 1.27 1.27)
							)
						)
					)
					(number "A3"
						(effects
							(font
								(size 1.27 1.27)
							)
						)
					)
				)
				(pin passive line
					(at 50.8 -40.64 180)
					(length 5.08)
					(hide yes)
					(name "VSSA"
						(effects
							(font
								(size 1.27 1.27)
							)
						)
					)
					(number "A7"
						(effects
							(font
								(size 1.27 1.27)
							)
						)
					)
				)
				(pin passive line
					(at 50.8 -40.64 180)
					(length 5.08)
					(hide yes)
					(name "VSSA"
						(effects
							(font
								(size 1.27 1.27)
							)
						)
					)
					(number "AA11"
						(effects
							(font
								(size 1.27 1.27)
							)
						)
					)
				)
				(pin passive line
					(at 50.8 -40.64 180)
					(length 5.08)
					(hide yes)
					(name "VSSA"
						(effects
							(font
								(size 1.27 1.27)
							)
						)
					)
					(number "AA13"
						(effects
							(font
								(size 1.27 1.27)
							)
						)
					)
				)
				(pin passive line
					(at 50.8 -40.64 180)
					(length 5.08)
					(hide yes)
					(name "VSSA"
						(effects
							(font
								(size 1.27 1.27)
							)
						)
					)
					(number "AA15"
						(effects
							(font
								(size 1.27 1.27)
							)
						)
					)
				)
				(pin passive line
					(at 50.8 -40.64 180)
					(length 5.08)
					(hide yes)
					(name "VSSA"
						(effects
							(font
								(size 1.27 1.27)
							)
						)
					)
					(number "AA17"
						(effects
							(font
								(size 1.27 1.27)
							)
						)
					)
				)
				(pin passive line
					(at 50.8 -40.64 180)
					(length 5.08)
					(hide yes)
					(name "VSSA"
						(effects
							(font
								(size 1.27 1.27)
							)
						)
					)
					(number "AA19"
						(effects
							(font
								(size 1.27 1.27)
							)
						)
					)
				)
				(pin passive line
					(at 50.8 -40.64 180)
					(length 5.08)
					(hide yes)
					(name "VSSA"
						(effects
							(font
								(size 1.27 1.27)
							)
						)
					)
					(number "AA21"
						(effects
							(font
								(size 1.27 1.27)
							)
						)
					)
				)
				(pin passive line
					(at 50.8 -40.64 180)
					(length 5.08)
					(hide yes)
					(name "VSSA"
						(effects
							(font
								(size 1.27 1.27)
							)
						)
					)
					(number "AA23"
						(effects
							(font
								(size 1.27 1.27)
							)
						)
					)
				)
				(pin passive line
					(at 50.8 -40.64 180)
					(length 5.08)
					(hide yes)
					(name "VSSA"
						(effects
							(font
								(size 1.27 1.27)
							)
						)
					)
					(number "AA25"
						(effects
							(font
								(size 1.27 1.27)
							)
						)
					)
				)
				(pin passive line
					(at 50.8 -40.64 180)
					(length 5.08)
					(hide yes)
					(name "VSSA"
						(effects
							(font
								(size 1.27 1.27)
							)
						)
					)
					(number "AA29"
						(effects
							(font
								(size 1.27 1.27)
							)
						)
					)
				)
				(pin passive line
					(at 50.8 -40.64 180)
					(length 5.08)
					(hide yes)
					(name "VSSA"
						(effects
							(font
								(size 1.27 1.27)
							)
						)
					)
					(number "AA3"
						(effects
							(font
								(size 1.27 1.27)
							)
						)
					)
				)
				(pin passive line
					(at 50.8 -40.64 180)
					(length 5.08)
					(hide yes)
					(name "VSSA"
						(effects
							(font
								(size 1.27 1.27)
							)
						)
					)
					(number "AA33"
						(effects
							(font
								(size 1.27 1.27)
							)
						)
					)
				)
				(pin passive line
					(at 50.8 -40.64 180)
					(length 5.08)
					(hide yes)
					(name "VSSA"
						(effects
							(font
								(size 1.27 1.27)
							)
						)
					)
					(number "AA37"
						(effects
							(font
								(size 1.27 1.27)
							)
						)
					)
				)
				(pin passive line
					(at 50.8 -40.64 180)
					(length 5.08)
					(hide yes)
					(name "VSSA"
						(effects
							(font
								(size 1.27 1.27)
							)
						)
					)
					(number "AA41"
						(effects
							(font
								(size 1.27 1.27)
							)
						)
					)
				)
				(pin passive line
					(at 50.8 -40.64 180)
					(length 5.08)
					(hide yes)
					(name "VSSA"
						(effects
							(font
								(size 1.27 1.27)
							)
						)
					)
					(number "AA9"
						(effects
							(font
								(size 1.27 1.27)
							)
						)
					)
				)
				(pin passive line
					(at 50.8 -40.64 180)
					(length 5.08)
					(hide yes)
					(name "VSSA"
						(effects
							(font
								(size 1.27 1.27)
							)
						)
					)
					(number "AB14"
						(effects
							(font
								(size 1.27 1.27)
							)
						)
					)
				)
				(pin passive line
					(at 50.8 -40.64 180)
					(length 5.08)
					(hide yes)
					(name "VSSA"
						(effects
							(font
								(size 1.27 1.27)
							)
						)
					)
					(number "AB20"
						(effects
							(font
								(size 1.27 1.27)
							)
						)
					)
				)
				(pin passive line
					(at 50.8 -40.64 180)
					(length 5.08)
					(hide yes)
					(name "VSSA"
						(effects
							(font
								(size 1.27 1.27)
							)
						)
					)
					(number "AB26"
						(effects
							(font
								(size 1.27 1.27)
							)
						)
					)
				)
				(pin passive line
					(at 50.8 -40.64 180)
					(length 5.08)
					(hide yes)
					(name "VSSA"
						(effects
							(font
								(size 1.27 1.27)
							)
						)
					)
					(number "AB30"
						(effects
							(font
								(size 1.27 1.27)
							)
						)
					)
				)
				(pin passive line
					(at 50.8 -40.64 180)
					(length 5.08)
					(hide yes)
					(name "VSSA"
						(effects
							(font
								(size 1.27 1.27)
							)
						)
					)
					(number "AB32"
						(effects
							(font
								(size 1.27 1.27)
							)
						)
					)
				)
				(pin passive line
					(at 50.8 -40.64 180)
					(length 5.08)
					(hide yes)
					(name "VSSA"
						(effects
							(font
								(size 1.27 1.27)
							)
						)
					)
					(number "AB34"
						(effects
							(font
								(size 1.27 1.27)
							)
						)
					)
				)
				(pin passive line
					(at 50.8 -40.64 180)
					(length 5.08)
					(hide yes)
					(name "VSSA"
						(effects
							(font
								(size 1.27 1.27)
							)
						)
					)
					(number "AB36"
						(effects
							(font
								(size 1.27 1.27)
							)
						)
					)
				)
				(pin passive line
					(at 50.8 -40.64 180)
					(length 5.08)
					(hide yes)
					(name "VSSA"
						(effects
							(font
								(size 1.27 1.27)
							)
						)
					)
					(number "AB38"
						(effects
							(font
								(size 1.27 1.27)
							)
						)
					)
				)
				(pin passive line
					(at 50.8 -40.64 180)
					(length 5.08)
					(hide yes)
					(name "VSSA"
						(effects
							(font
								(size 1.27 1.27)
							)
						)
					)
					(number "AB4"
						(effects
							(font
								(size 1.27 1.27)
							)
						)
					)
				)
				(pin passive line
					(at 50.8 -40.64 180)
					(length 5.08)
					(hide yes)
					(name "VSSA"
						(effects
							(font
								(size 1.27 1.27)
							)
						)
					)
					(number "AB40"
						(effects
							(font
								(size 1.27 1.27)
							)
						)
					)
				)
				(pin passive line
					(at 50.8 -40.64 180)
					(length 5.08)
					(hide yes)
					(name "VSSA"
						(effects
							(font
								(size 1.27 1.27)
							)
						)
					)
					(number "AB6"
						(effects
							(font
								(size 1.27 1.27)
							)
						)
					)
				)
				(pin passive line
					(at 50.8 -40.64 180)
					(length 5.08)
					(hide yes)
					(name "VSSA"
						(effects
							(font
								(size 1.27 1.27)
							)
						)
					)
					(number "AB8"
						(effects
							(font
								(size 1.27 1.27)
							)
						)
					)
				)
				(pin passive line
					(at 50.8 -40.64 180)
					(length 5.08)
					(hide yes)
					(name "VSSA"
						(effects
							(font
								(size 1.27 1.27)
							)
						)
					)
					(number "AC1"
						(effects
							(font
								(size 1.27 1.27)
							)
						)
					)
				)
				(pin passive line
					(at 50.8 -40.64 180)
					(length 5.08)
					(hide yes)
					(name "VSSA"
						(effects
							(font
								(size 1.27 1.27)
							)
						)
					)
					(number "AC11"
						(effects
							(font
								(size 1.27 1.27)
							)
						)
					)
				)
				(pin passive line
					(at 50.8 -40.64 180)
					(length 5.08)
					(hide yes)
					(name "VSSA"
						(effects
							(font
								(size 1.27 1.27)
							)
						)
					)
					(number "AC13"
						(effects
							(font
								(size 1.27 1.27)
							)
						)
					)
				)
				(pin passive line
					(at 50.8 -40.64 180)
					(length 5.08)
					(hide yes)
					(name "VSSA"
						(effects
							(font
								(size 1.27 1.27)
							)
						)
					)
					(number "AC15"
						(effects
							(font
								(size 1.27 1.27)
							)
						)
					)
				)
				(pin passive line
					(at 50.8 -40.64 180)
					(length 5.08)
					(hide yes)
					(name "VSSA"
						(effects
							(font
								(size 1.27 1.27)
							)
						)
					)
					(number "AC17"
						(effects
							(font
								(size 1.27 1.27)
							)
						)
					)
				)
				(pin passive line
					(at 50.8 -40.64 180)
					(length 5.08)
					(hide yes)
					(name "VSSA"
						(effects
							(font
								(size 1.27 1.27)
							)
						)
					)
					(number "AC19"
						(effects
							(font
								(size 1.27 1.27)
							)
						)
					)
				)
				(pin passive line
					(at 50.8 -40.64 180)
					(length 5.08)
					(hide yes)
					(name "VSSA"
						(effects
							(font
								(size 1.27 1.27)
							)
						)
					)
					(number "AC21"
						(effects
							(font
								(size 1.27 1.27)
							)
						)
					)
				)
				(pin passive line
					(at 50.8 -40.64 180)
					(length 5.08)
					(hide yes)
					(name "VSSA"
						(effects
							(font
								(size 1.27 1.27)
							)
						)
					)
					(number "AC23"
						(effects
							(font
								(size 1.27 1.27)
							)
						)
					)
				)
				(pin passive line
					(at 50.8 -40.64 180)
					(length 5.08)
					(hide yes)
					(name "VSSA"
						(effects
							(font
								(size 1.27 1.27)
							)
						)
					)
					(number "AC25"
						(effects
							(font
								(size 1.27 1.27)
							)
						)
					)
				)
				(pin passive line
					(at 50.8 -40.64 180)
					(length 5.08)
					(hide yes)
					(name "VSSA"
						(effects
							(font
								(size 1.27 1.27)
							)
						)
					)
					(number "AC27"
						(effects
							(font
								(size 1.27 1.27)
							)
						)
					)
				)
				(pin passive line
					(at 50.8 -40.64 180)
					(length 5.08)
					(hide yes)
					(name "VSSA"
						(effects
							(font
								(size 1.27 1.27)
							)
						)
					)
					(number "AC29"
						(effects
							(font
								(size 1.27 1.27)
							)
						)
					)
				)
				(pin passive line
					(at 50.8 -40.64 180)
					(length 5.08)
					(hide yes)
					(name "VSSA"
						(effects
							(font
								(size 1.27 1.27)
							)
						)
					)
					(number "AC3"
						(effects
							(font
								(size 1.27 1.27)
							)
						)
					)
				)
				(pin passive line
					(at 50.8 -40.64 180)
					(length 5.08)
					(hide yes)
					(name "VSSA"
						(effects
							(font
								(size 1.27 1.27)
							)
						)
					)
					(number "AC33"
						(effects
							(font
								(size 1.27 1.27)
							)
						)
					)
				)
				(pin passive line
					(at 50.8 -40.64 180)
					(length 5.08)
					(hide yes)
					(name "VSSA"
						(effects
							(font
								(size 1.27 1.27)
							)
						)
					)
					(number "AC37"
						(effects
							(font
								(size 1.27 1.27)
							)
						)
					)
				)
				(pin passive line
					(at 50.8 -40.64 180)
					(length 5.08)
					(hide yes)
					(name "VSSA"
						(effects
							(font
								(size 1.27 1.27)
							)
						)
					)
					(number "AC41"
						(effects
							(font
								(size 1.27 1.27)
							)
						)
					)
				)
				(pin passive line
					(at 50.8 -40.64 180)
					(length 5.08)
					(hide yes)
					(name "VSSA"
						(effects
							(font
								(size 1.27 1.27)
							)
						)
					)
					(number "AC7"
						(effects
							(font
								(size 1.27 1.27)
							)
						)
					)
				)
				(pin passive line
					(at 50.8 -40.64 180)
					(length 5.08)
					(hide yes)
					(name "VSSA"
						(effects
							(font
								(size 1.27 1.27)
							)
						)
					)
					(number "AC9"
						(effects
							(font
								(size 1.27 1.27)
							)
						)
					)
				)
				(pin passive line
					(at 50.8 -40.64 180)
					(length 5.08)
					(hide yes)
					(name "VSSA"
						(effects
							(font
								(size 1.27 1.27)
							)
						)
					)
					(number "AD12"
						(effects
							(font
								(size 1.27 1.27)
							)
						)
					)
				)
				(pin passive line
					(at 50.8 -40.64 180)
					(length 5.08)
					(hide yes)
					(name "VSSA"
						(effects
							(font
								(size 1.27 1.27)
							)
						)
					)
					(number "AD18"
						(effects
							(font
								(size 1.27 1.27)
							)
						)
					)
				)
				(pin passive line
					(at 50.8 -40.64 180)
					(length 5.08)
					(hide yes)
					(name "VSSA"
						(effects
							(font
								(size 1.27 1.27)
							)
						)
					)
					(number "AD2"
						(effects
							(font
								(size 1.27 1.27)
							)
						)
					)
				)
				(pin passive line
					(at 50.8 -40.64 180)
					(length 5.08)
					(hide yes)
					(name "VSSA"
						(effects
							(font
								(size 1.27 1.27)
							)
						)
					)
					(number "AD24"
						(effects
							(font
								(size 1.27 1.27)
							)
						)
					)
				)
				(pin passive line
					(at 50.8 -40.64 180)
					(length 5.08)
					(hide yes)
					(name "VSSA"
						(effects
							(font
								(size 1.27 1.27)
							)
						)
					)
					(number "AD30"
						(effects
							(font
								(size 1.27 1.27)
							)
						)
					)
				)
				(pin passive line
					(at 50.8 -40.64 180)
					(length 5.08)
					(hide yes)
					(name "VSSA"
						(effects
							(font
								(size 1.27 1.27)
							)
						)
					)
					(number "AD34"
						(effects
							(font
								(size 1.27 1.27)
							)
						)
					)
				)
				(pin passive line
					(at 50.8 -40.64 180)
					(length 5.08)
					(hide yes)
					(name "VSSA"
						(effects
							(font
								(size 1.27 1.27)
							)
						)
					)
					(number "AD38"
						(effects
							(font
								(size 1.27 1.27)
							)
						)
					)
				)
				(pin passive line
					(at 50.8 -40.64 180)
					(length 5.08)
					(hide yes)
					(name "VSSA"
						(effects
							(font
								(size 1.27 1.27)
							)
						)
					)
					(number "AD42"
						(effects
							(font
								(size 1.27 1.27)
							)
						)
					)
				)
				(pin passive line
					(at 50.8 -40.64 180)
					(length 5.08)
					(hide yes)
					(name "VSSA"
						(effects
							(font
								(size 1.27 1.27)
							)
						)
					)
					(number "AD6"
						(effects
							(font
								(size 1.27 1.27)
							)
						)
					)
				)
				(pin passive line
					(at 50.8 -40.64 180)
					(length 5.08)
					(hide yes)
					(name "VSSA"
						(effects
							(font
								(size 1.27 1.27)
							)
						)
					)
					(number "B12"
						(effects
							(font
								(size 1.27 1.27)
							)
						)
					)
				)
				(pin passive line
					(at 50.8 -40.64 180)
					(length 5.08)
					(hide yes)
					(name "VSSA"
						(effects
							(font
								(size 1.27 1.27)
							)
						)
					)
					(number "B16"
						(effects
							(font
								(size 1.27 1.27)
							)
						)
					)
				)
				(pin passive line
					(at 50.8 -40.64 180)
					(length 5.08)
					(hide yes)
					(name "VSSA"
						(effects
							(font
								(size 1.27 1.27)
							)
						)
					)
					(number "B2"
						(effects
							(font
								(size 1.27 1.27)
							)
						)
					)
				)
				(pin passive line
					(at 50.8 -40.64 180)
					(length 5.08)
					(hide yes)
					(name "VSSA"
						(effects
							(font
								(size 1.27 1.27)
							)
						)
					)
					(number "B20"
						(effects
							(font
								(size 1.27 1.27)
							)
						)
					)
				)
				(pin passive line
					(at 50.8 -40.64 180)
					(length 5.08)
					(hide yes)
					(name "VSSA"
						(effects
							(font
								(size 1.27 1.27)
							)
						)
					)
					(number "B4"
						(effects
							(font
								(size 1.27 1.27)
							)
						)
					)
				)
				(pin passive line
					(at 50.8 -40.64 180)
					(length 5.08)
					(hide yes)
					(name "VSSA"
						(effects
							(font
								(size 1.27 1.27)
							)
						)
					)
					(number "B8"
						(effects
							(font
								(size 1.27 1.27)
							)
						)
					)
				)
				(pin passive line
					(at 50.8 -40.64 180)
					(length 5.08)
					(hide yes)
					(name "VSSA"
						(effects
							(font
								(size 1.27 1.27)
							)
						)
					)
					(number "C11"
						(effects
							(font
								(size 1.27 1.27)
							)
						)
					)
				)
				(pin passive line
					(at 50.8 -40.64 180)
					(length 5.08)
					(hide yes)
					(name "VSSA"
						(effects
							(font
								(size 1.27 1.27)
							)
						)
					)
					(number "C13"
						(effects
							(font
								(size 1.27 1.27)
							)
						)
					)
				)
				(pin passive line
					(at 50.8 -40.64 180)
					(length 5.08)
					(hide yes)
					(name "VSSA"
						(effects
							(font
								(size 1.27 1.27)
							)
						)
					)
					(number "C15"
						(effects
							(font
								(size 1.27 1.27)
							)
						)
					)
				)
				(pin passive line
					(at 50.8 -40.64 180)
					(length 5.08)
					(hide yes)
					(name "VSSA"
						(effects
							(font
								(size 1.27 1.27)
							)
						)
					)
					(number "C17"
						(effects
							(font
								(size 1.27 1.27)
							)
						)
					)
				)
				(pin passive line
					(at 50.8 -40.64 180)
					(length 5.08)
					(hide yes)
					(name "VSSA"
						(effects
							(font
								(size 1.27 1.27)
							)
						)
					)
					(number "C19"
						(effects
							(font
								(size 1.27 1.27)
							)
						)
					)
				)
				(pin passive line
					(at 50.8 -40.64 180)
					(length 5.08)
					(hide yes)
					(name "VSSA"
						(effects
							(font
								(size 1.27 1.27)
							)
						)
					)
					(number "C5"
						(effects
							(font
								(size 1.27 1.27)
							)
						)
					)
				)
				(pin passive line
					(at 50.8 -40.64 180)
					(length 5.08)
					(hide yes)
					(name "VSSA"
						(effects
							(font
								(size 1.27 1.27)
							)
						)
					)
					(number "C7"
						(effects
							(font
								(size 1.27 1.27)
							)
						)
					)
				)
				(pin passive line
					(at 50.8 -40.64 180)
					(length 5.08)
					(hide yes)
					(name "VSSA"
						(effects
							(font
								(size 1.27 1.27)
							)
						)
					)
					(number "C9"
						(effects
							(font
								(size 1.27 1.27)
							)
						)
					)
				)
				(pin passive line
					(at 50.8 -40.64 180)
					(length 5.08)
					(hide yes)
					(name "VSSA"
						(effects
							(font
								(size 1.27 1.27)
							)
						)
					)
					(number "H26"
						(effects
							(font
								(size 1.27 1.27)
							)
						)
					)
				)
				(pin passive line
					(at 50.8 -40.64 180)
					(length 5.08)
					(hide yes)
					(name "VSSA"
						(effects
							(font
								(size 1.27 1.27)
							)
						)
					)
					(number "H28"
						(effects
							(font
								(size 1.27 1.27)
							)
						)
					)
				)
				(pin passive line
					(at 50.8 -40.64 180)
					(length 5.08)
					(hide yes)
					(name "VSSA"
						(effects
							(font
								(size 1.27 1.27)
							)
						)
					)
					(number "H30"
						(effects
							(font
								(size 1.27 1.27)
							)
						)
					)
				)
				(pin passive line
					(at 50.8 -40.64 180)
					(length 5.08)
					(hide yes)
					(name "VSSA"
						(effects
							(font
								(size 1.27 1.27)
							)
						)
					)
					(number "H32"
						(effects
							(font
								(size 1.27 1.27)
							)
						)
					)
				)
				(pin passive line
					(at 50.8 -40.64 180)
					(length 5.08)
					(hide yes)
					(name "VSSA"
						(effects
							(font
								(size 1.27 1.27)
							)
						)
					)
					(number "H34"
						(effects
							(font
								(size 1.27 1.27)
							)
						)
					)
				)
				(pin passive line
					(at 50.8 -40.64 180)
					(length 5.08)
					(hide yes)
					(name "VSSA"
						(effects
							(font
								(size 1.27 1.27)
							)
						)
					)
					(number "H36"
						(effects
							(font
								(size 1.27 1.27)
							)
						)
					)
				)
				(pin passive line
					(at 50.8 -40.64 180)
					(length 5.08)
					(hide yes)
					(name "VSSA"
						(effects
							(font
								(size 1.27 1.27)
							)
						)
					)
					(number "H38"
						(effects
							(font
								(size 1.27 1.27)
							)
						)
					)
				)
				(pin passive line
					(at 50.8 -40.64 180)
					(length 5.08)
					(hide yes)
					(name "VSSA"
						(effects
							(font
								(size 1.27 1.27)
							)
						)
					)
					(number "K10"
						(effects
							(font
								(size 1.27 1.27)
							)
						)
					)
				)
				(pin passive line
					(at 50.8 -40.64 180)
					(length 5.08)
					(hide yes)
					(name "VSSA"
						(effects
							(font
								(size 1.27 1.27)
							)
						)
					)
					(number "K12"
						(effects
							(font
								(size 1.27 1.27)
							)
						)
					)
				)
				(pin passive line
					(at 50.8 -40.64 180)
					(length 5.08)
					(hide yes)
					(name "VSSA"
						(effects
							(font
								(size 1.27 1.27)
							)
						)
					)
					(number "K14"
						(effects
							(font
								(size 1.27 1.27)
							)
						)
					)
				)
				(pin passive line
					(at 50.8 -40.64 180)
					(length 5.08)
					(hide yes)
					(name "VSSA"
						(effects
							(font
								(size 1.27 1.27)
							)
						)
					)
					(number "K16"
						(effects
							(font
								(size 1.27 1.27)
							)
						)
					)
				)
				(pin passive line
					(at 50.8 -40.64 180)
					(length 5.08)
					(hide yes)
					(name "VSSA"
						(effects
							(font
								(size 1.27 1.27)
							)
						)
					)
					(number "K38"
						(effects
							(font
								(size 1.27 1.27)
							)
						)
					)
				)
				(pin passive line
					(at 50.8 -40.64 180)
					(length 5.08)
					(hide yes)
					(name "VSSA"
						(effects
							(font
								(size 1.27 1.27)
							)
						)
					)
					(number "K8"
						(effects
							(font
								(size 1.27 1.27)
							)
						)
					)
				)
				(pin passive line
					(at 50.8 -40.64 180)
					(length 5.08)
					(hide yes)
					(name "VSSA"
						(effects
							(font
								(size 1.27 1.27)
							)
						)
					)
					(number "M10"
						(effects
							(font
								(size 1.27 1.27)
							)
						)
					)
				)
				(pin passive line
					(at 50.8 -40.64 180)
					(length 5.08)
					(hide yes)
					(name "VSSA"
						(effects
							(font
								(size 1.27 1.27)
							)
						)
					)
					(number "M12"
						(effects
							(font
								(size 1.27 1.27)
							)
						)
					)
				)
				(pin passive line
					(at 50.8 -40.64 180)
					(length 5.08)
					(hide yes)
					(name "VSSA"
						(effects
							(font
								(size 1.27 1.27)
							)
						)
					)
					(number "M14"
						(effects
							(font
								(size 1.27 1.27)
							)
						)
					)
				)
				(pin passive line
					(at 50.8 -40.64 180)
					(length 5.08)
					(hide yes)
					(name "VSSA"
						(effects
							(font
								(size 1.27 1.27)
							)
						)
					)
					(number "M16"
						(effects
							(font
								(size 1.27 1.27)
							)
						)
					)
				)
				(pin passive line
					(at 50.8 -40.64 180)
					(length 5.08)
					(hide yes)
					(name "VSSA"
						(effects
							(font
								(size 1.27 1.27)
							)
						)
					)
					(number "V12"
						(effects
							(font
								(size 1.27 1.27)
							)
						)
					)
				)
				(pin passive line
					(at 50.8 -40.64 180)
					(length 5.08)
					(hide yes)
					(name "VSSA"
						(effects
							(font
								(size 1.27 1.27)
							)
						)
					)
					(number "V14"
						(effects
							(font
								(size 1.27 1.27)
							)
						)
					)
				)
				(pin passive line
					(at 50.8 -40.64 180)
					(length 5.08)
					(hide yes)
					(name "VSSA"
						(effects
							(font
								(size 1.27 1.27)
							)
						)
					)
					(number "V16"
						(effects
							(font
								(size 1.27 1.27)
							)
						)
					)
				)
				(pin passive line
					(at 50.8 -40.64 180)
					(length 5.08)
					(hide yes)
					(name "VSSA"
						(effects
							(font
								(size 1.27 1.27)
							)
						)
					)
					(number "V18"
						(effects
							(font
								(size 1.27 1.27)
							)
						)
					)
				)
				(pin passive line
					(at 50.8 -40.64 180)
					(length 5.08)
					(hide yes)
					(name "VSSA"
						(effects
							(font
								(size 1.27 1.27)
							)
						)
					)
					(number "V20"
						(effects
							(font
								(size 1.27 1.27)
							)
						)
					)
				)
				(pin passive line
					(at 50.8 -40.64 180)
					(length 5.08)
					(hide yes)
					(name "VSSA"
						(effects
							(font
								(size 1.27 1.27)
							)
						)
					)
					(number "W29"
						(effects
							(font
								(size 1.27 1.27)
							)
						)
					)
				)
				(pin passive line
					(at 50.8 -40.64 180)
					(length 5.08)
					(hide yes)
					(name "VSSA"
						(effects
							(font
								(size 1.27 1.27)
							)
						)
					)
					(number "W31"
						(effects
							(font
								(size 1.27 1.27)
							)
						)
					)
				)
				(pin passive line
					(at 50.8 -40.64 180)
					(length 5.08)
					(hide yes)
					(name "VSSA"
						(effects
							(font
								(size 1.27 1.27)
							)
						)
					)
					(number "W33"
						(effects
							(font
								(size 1.27 1.27)
							)
						)
					)
				)
				(pin passive line
					(at 50.8 -40.64 180)
					(length 5.08)
					(hide yes)
					(name "VSSA"
						(effects
							(font
								(size 1.27 1.27)
							)
						)
					)
					(number "W35"
						(effects
							(font
								(size 1.27 1.27)
							)
						)
					)
				)
				(pin passive line
					(at 50.8 -40.64 180)
					(length 5.08)
					(hide yes)
					(name "VSSA"
						(effects
							(font
								(size 1.27 1.27)
							)
						)
					)
					(number "W37"
						(effects
							(font
								(size 1.27 1.27)
							)
						)
					)
				)
				(pin passive line
					(at 50.8 -40.64 180)
					(length 5.08)
					(hide yes)
					(name "VSSA"
						(effects
							(font
								(size 1.27 1.27)
							)
						)
					)
					(number "W39"
						(effects
							(font
								(size 1.27 1.27)
							)
						)
					)
				)
				(pin passive line
					(at 50.8 -40.64 180)
					(length 5.08)
					(hide yes)
					(name "VSSA"
						(effects
							(font
								(size 1.27 1.27)
							)
						)
					)
					(number "Y14"
						(effects
							(font
								(size 1.27 1.27)
							)
						)
					)
				)
				(pin passive line
					(at 50.8 -40.64 180)
					(length 5.08)
					(hide yes)
					(name "VSSA"
						(effects
							(font
								(size 1.27 1.27)
							)
						)
					)
					(number "Y26"
						(effects
							(font
								(size 1.27 1.27)
							)
						)
					)
				)
				(pin passive line
					(at 50.8 -40.64 180)
					(length 5.08)
					(hide yes)
					(name "VSSA"
						(effects
							(font
								(size 1.27 1.27)
							)
						)
					)
					(number "Y28"
						(effects
							(font
								(size 1.27 1.27)
							)
						)
					)
				)
				(pin passive line
					(at 50.8 -40.64 180)
					(length 5.08)
					(hide yes)
					(name "VSSA"
						(effects
							(font
								(size 1.27 1.27)
							)
						)
					)
					(number "Y32"
						(effects
							(font
								(size 1.27 1.27)
							)
						)
					)
				)
				(pin passive line
					(at 50.8 -40.64 180)
					(length 5.08)
					(hide yes)
					(name "VSSA"
						(effects
							(font
								(size 1.27 1.27)
							)
						)
					)
					(number "Y36"
						(effects
							(font
								(size 1.27 1.27)
							)
						)
					)
				)
				(pin passive line
					(at 50.8 -40.64 180)
					(length 5.08)
					(hide yes)
					(name "VSSA"
						(effects
							(font
								(size 1.27 1.27)
							)
						)
					)
					(number "Y4"
						(effects
							(font
								(size 1.27 1.27)
							)
						)
					)
				)
				(pin passive line
					(at 50.8 -40.64 180)
					(length 5.08)
					(hide yes)
					(name "VSSA"
						(effects
							(font
								(size 1.27 1.27)
							)
						)
					)
					(number "Y40"
						(effects
							(font
								(size 1.27 1.27)
							)
						)
					)
				)
				(pin passive line
					(at 50.8 -40.64 180)
					(length 5.08)
					(hide yes)
					(name "VSSA"
						(effects
							(font
								(size 1.27 1.27)
							)
						)
					)
					(number "Y6"
						(effects
							(font
								(size 1.27 1.27)
							)
						)
					)
				)
				(pin passive line
					(at 50.8 -40.64 180)
					(length 5.08)
					(hide yes)
					(name "VSSA"
						(effects
							(font
								(size 1.27 1.27)
							)
						)
					)
					(number "Y8"
						(effects
							(font
								(size 1.27 1.27)
							)
						)
					)
				)
				(pin power_in line
					(at 50.8 -43.18 180)
					(length 5.08)
					(name "AVSS"
						(effects
							(font
								(size 1.27 1.27)
							)
						)
					)
					(number "A21"
						(effects
							(font
								(size 1.27 1.27)
							)
						)
					)
				)
				(pin passive line
					(at 50.8 -43.18 180)
					(length 5.08)
					(hide yes)
					(name "AVSS"
						(effects
							(font
								(size 1.27 1.27)
							)
						)
					)
					(number "A31"
						(effects
							(font
								(size 1.27 1.27)
							)
						)
					)
				)
				(pin passive line
					(at 50.8 -43.18 180)
					(length 5.08)
					(hide yes)
					(name "AVSS"
						(effects
							(font
								(size 1.27 1.27)
							)
						)
					)
					(number "B22"
						(effects
							(font
								(size 1.27 1.27)
							)
						)
					)
				)
				(pin passive line
					(at 50.8 -43.18 180)
					(length 5.08)
					(hide yes)
					(name "AVSS"
						(effects
							(font
								(size 1.27 1.27)
							)
						)
					)
					(number "B32"
						(effects
							(font
								(size 1.27 1.27)
							)
						)
					)
				)
				(pin passive line
					(at 50.8 -43.18 180)
					(length 5.08)
					(hide yes)
					(name "AVSS"
						(effects
							(font
								(size 1.27 1.27)
							)
						)
					)
					(number "C31"
						(effects
							(font
								(size 1.27 1.27)
							)
						)
					)
				)
				(pin passive line
					(at 50.8 -43.18 180)
					(length 5.08)
					(hide yes)
					(name "AVSS"
						(effects
							(font
								(size 1.27 1.27)
							)
						)
					)
					(number "C41"
						(effects
							(font
								(size 1.27 1.27)
							)
						)
					)
				)
				(pin passive line
					(at 50.8 -43.18 180)
					(length 5.08)
					(hide yes)
					(name "AVSS"
						(effects
							(font
								(size 1.27 1.27)
							)
						)
					)
					(number "D24"
						(effects
							(font
								(size 1.27 1.27)
							)
						)
					)
				)
				(pin passive line
					(at 50.8 -43.18 180)
					(length 5.08)
					(hide yes)
					(name "AVSS"
						(effects
							(font
								(size 1.27 1.27)
							)
						)
					)
					(number "D26"
						(effects
							(font
								(size 1.27 1.27)
							)
						)
					)
				)
				(pin passive line
					(at 50.8 -43.18 180)
					(length 5.08)
					(hide yes)
					(name "AVSS"
						(effects
							(font
								(size 1.27 1.27)
							)
						)
					)
					(number "D28"
						(effects
							(font
								(size 1.27 1.27)
							)
						)
					)
				)
				(pin passive line
					(at 50.8 -43.18 180)
					(length 5.08)
					(hide yes)
					(name "AVSS"
						(effects
							(font
								(size 1.27 1.27)
							)
						)
					)
					(number "D36"
						(effects
							(font
								(size 1.27 1.27)
							)
						)
					)
				)
				(pin passive line
					(at 50.8 -43.18 180)
					(length 5.08)
					(hide yes)
					(name "AVSS"
						(effects
							(font
								(size 1.27 1.27)
							)
						)
					)
					(number "D38"
						(effects
							(font
								(size 1.27 1.27)
							)
						)
					)
				)
				(pin passive line
					(at 50.8 -43.18 180)
					(length 5.08)
					(hide yes)
					(name "AVSS"
						(effects
							(font
								(size 1.27 1.27)
							)
						)
					)
					(number "D40"
						(effects
							(font
								(size 1.27 1.27)
							)
						)
					)
				)
				(pin passive line
					(at 50.8 -43.18 180)
					(length 5.08)
					(hide yes)
					(name "AVSS"
						(effects
							(font
								(size 1.27 1.27)
							)
						)
					)
					(number "E31"
						(effects
							(font
								(size 1.27 1.27)
							)
						)
					)
				)
				(pin passive line
					(at 50.8 -43.18 180)
					(length 5.08)
					(hide yes)
					(name "AVSS"
						(effects
							(font
								(size 1.27 1.27)
							)
						)
					)
					(number "E33"
						(effects
							(font
								(size 1.27 1.27)
							)
						)
					)
				)
				(pin passive line
					(at 50.8 -43.18 180)
					(length 5.08)
					(hide yes)
					(name "AVSS"
						(effects
							(font
								(size 1.27 1.27)
							)
						)
					)
					(number "F40"
						(effects
							(font
								(size 1.27 1.27)
							)
						)
					)
				)
				(pin passive line
					(at 50.8 -43.18 180)
					(length 5.08)
					(hide yes)
					(name "AVSS"
						(effects
							(font
								(size 1.27 1.27)
							)
						)
					)
					(number "F42"
						(effects
							(font
								(size 1.27 1.27)
							)
						)
					)
				)
				(pin passive line
					(at 50.8 -43.18 180)
					(length 5.08)
					(hide yes)
					(name "AVSS"
						(effects
							(font
								(size 1.27 1.27)
							)
						)
					)
					(number "G41"
						(effects
							(font
								(size 1.27 1.27)
							)
						)
					)
				)
				(pin power_in line
					(at 50.8 -45.72 180)
					(length 5.08)
					(name "RSVDW3_VSS"
						(effects
							(font
								(size 1.27 1.27)
							)
						)
					)
					(number "W3"
						(effects
							(font
								(size 1.27 1.27)
							)
						)
					)
				)
				(pin power_in line
					(at 50.8 -48.26 180)
					(length 5.08)
					(name "VSS_SVR"
						(effects
							(font
								(size 1.27 1.27)
							)
						)
					)
					(number "U1"
						(effects
							(font
								(size 1.27 1.27)
							)
						)
					)
				)
				(pin power_in line
					(at 50.8 -50.8 180)
					(length 5.08)
					(name "VSS_S"
						(effects
							(font
								(size 1.27 1.27)
							)
						)
					)
					(number "Y2"
						(effects
							(font
								(size 1.27 1.27)
							)
						)
					)
				)
				(pin power_in line
					(at 50.8 -53.34 180)
					(length 5.08)
					(name "VSS"
						(effects
							(font
								(size 1.27 1.27)
							)
						)
					)
					(number "F24"
						(effects
							(font
								(size 1.27 1.27)
							)
						)
					)
				)
				(pin passive line
					(at 50.8 -53.34 180)
					(length 5.08)
					(hide yes)
					(name "VSS"
						(effects
							(font
								(size 1.27 1.27)
							)
						)
					)
					(number "F26"
						(effects
							(font
								(size 1.27 1.27)
							)
						)
					)
				)
				(pin passive line
					(at 50.8 -53.34 180)
					(length 5.08)
					(hide yes)
					(name "VSS"
						(effects
							(font
								(size 1.27 1.27)
							)
						)
					)
					(number "F28"
						(effects
							(font
								(size 1.27 1.27)
							)
						)
					)
				)
				(pin passive line
					(at 50.8 -53.34 180)
					(length 5.08)
					(hide yes)
					(name "VSS"
						(effects
							(font
								(size 1.27 1.27)
							)
						)
					)
					(number "F30"
						(effects
							(font
								(size 1.27 1.27)
							)
						)
					)
				)
				(pin passive line
					(at 50.8 -53.34 180)
					(length 5.08)
					(hide yes)
					(name "VSS"
						(effects
							(font
								(size 1.27 1.27)
							)
						)
					)
					(number "F32"
						(effects
							(font
								(size 1.27 1.27)
							)
						)
					)
				)
				(pin passive line
					(at 50.8 -53.34 180)
					(length 5.08)
					(hide yes)
					(name "VSS"
						(effects
							(font
								(size 1.27 1.27)
							)
						)
					)
					(number "F34"
						(effects
							(font
								(size 1.27 1.27)
							)
						)
					)
				)
				(pin passive line
					(at 50.8 -53.34 180)
					(length 5.08)
					(hide yes)
					(name "VSS"
						(effects
							(font
								(size 1.27 1.27)
							)
						)
					)
					(number "F36"
						(effects
							(font
								(size 1.27 1.27)
							)
						)
					)
				)
				(pin passive line
					(at 50.8 -53.34 180)
					(length 5.08)
					(hide yes)
					(name "VSS"
						(effects
							(font
								(size 1.27 1.27)
							)
						)
					)
					(number "K18"
						(effects
							(font
								(size 1.27 1.27)
							)
						)
					)
				)
				(pin passive line
					(at 50.8 -53.34 180)
					(length 5.08)
					(hide yes)
					(name "VSS"
						(effects
							(font
								(size 1.27 1.27)
							)
						)
					)
					(number "K20"
						(effects
							(font
								(size 1.27 1.27)
							)
						)
					)
				)
				(pin passive line
					(at 50.8 -53.34 180)
					(length 5.08)
					(hide yes)
					(name "VSS"
						(effects
							(font
								(size 1.27 1.27)
							)
						)
					)
					(number "M18"
						(effects
							(font
								(size 1.27 1.27)
							)
						)
					)
				)
				(pin passive line
					(at 50.8 -53.34 180)
					(length 5.08)
					(hide yes)
					(name "VSS"
						(effects
							(font
								(size 1.27 1.27)
							)
						)
					)
					(number "M20"
						(effects
							(font
								(size 1.27 1.27)
							)
						)
					)
				)
				(pin passive line
					(at 50.8 -53.34 180)
					(length 5.08)
					(hide yes)
					(name "VSS"
						(effects
							(font
								(size 1.27 1.27)
							)
						)
					)
					(number "P10"
						(effects
							(font
								(size 1.27 1.27)
							)
						)
					)
				)
				(pin passive line
					(at 50.8 -53.34 180)
					(length 5.08)
					(hide yes)
					(name "VSS"
						(effects
							(font
								(size 1.27 1.27)
							)
						)
					)
					(number "P12"
						(effects
							(font
								(size 1.27 1.27)
							)
						)
					)
				)
				(pin passive line
					(at 50.8 -53.34 180)
					(length 5.08)
					(hide yes)
					(name "VSS"
						(effects
							(font
								(size 1.27 1.27)
							)
						)
					)
					(number "P14"
						(effects
							(font
								(size 1.27 1.27)
							)
						)
					)
				)
				(pin passive line
					(at 50.8 -53.34 180)
					(length 5.08)
					(hide yes)
					(name "VSS"
						(effects
							(font
								(size 1.27 1.27)
							)
						)
					)
					(number "P16"
						(effects
							(font
								(size 1.27 1.27)
							)
						)
					)
				)
				(pin passive line
					(at 50.8 -53.34 180)
					(length 5.08)
					(hide yes)
					(name "VSS"
						(effects
							(font
								(size 1.27 1.27)
							)
						)
					)
					(number "P18"
						(effects
							(font
								(size 1.27 1.27)
							)
						)
					)
				)
				(pin passive line
					(at 50.8 -53.34 180)
					(length 5.08)
					(hide yes)
					(name "VSS"
						(effects
							(font
								(size 1.27 1.27)
							)
						)
					)
					(number "P20"
						(effects
							(font
								(size 1.27 1.27)
							)
						)
					)
				)
				(pin passive line
					(at 50.8 -53.34 180)
					(length 5.08)
					(hide yes)
					(name "VSS"
						(effects
							(font
								(size 1.27 1.27)
							)
						)
					)
					(number "R35"
						(effects
							(font
								(size 1.27 1.27)
							)
						)
					)
				)
				(pin passive line
					(at 50.8 -53.34 180)
					(length 5.08)
					(hide yes)
					(name "VSS"
						(effects
							(font
								(size 1.27 1.27)
							)
						)
					)
					(number "T10"
						(effects
							(font
								(size 1.27 1.27)
							)
						)
					)
				)
				(pin passive line
					(at 50.8 -53.34 180)
					(length 5.08)
					(hide yes)
					(name "VSS"
						(effects
							(font
								(size 1.27 1.27)
							)
						)
					)
					(number "T12"
						(effects
							(font
								(size 1.27 1.27)
							)
						)
					)
				)
				(pin passive line
					(at 50.8 -53.34 180)
					(length 5.08)
					(hide yes)
					(name "VSS"
						(effects
							(font
								(size 1.27 1.27)
							)
						)
					)
					(number "T14"
						(effects
							(font
								(size 1.27 1.27)
							)
						)
					)
				)
				(pin passive line
					(at 50.8 -53.34 180)
					(length 5.08)
					(hide yes)
					(name "VSS"
						(effects
							(font
								(size 1.27 1.27)
							)
						)
					)
					(number "T16"
						(effects
							(font
								(size 1.27 1.27)
							)
						)
					)
				)
				(pin passive line
					(at 50.8 -53.34 180)
					(length 5.08)
					(hide yes)
					(name "VSS"
						(effects
							(font
								(size 1.27 1.27)
							)
						)
					)
					(number "T18"
						(effects
							(font
								(size 1.27 1.27)
							)
						)
					)
				)
				(pin passive line
					(at 50.8 -53.34 180)
					(length 5.08)
					(hide yes)
					(name "VSS"
						(effects
							(font
								(size 1.27 1.27)
							)
						)
					)
					(number "T20"
						(effects
							(font
								(size 1.27 1.27)
							)
						)
					)
				)
			)
		)
	(symbol "antmicroLEDIndicationDiscrete:LED_G_0603_LG_L29K-G2J1-24-Z"
			(pin_numbers
				(hide yes)
			)
			(pin_names
				(hide yes)
			)
			(exclude_from_sim no)
			(in_bom yes)
			(on_board yes)
			(property "Reference" "D"
				(at 20.32 -2.54 0)
				(effects
					(font
						(size 1.27 1.27)
						(thickness 0.15)
					)
					(justify left bottom)
				)
			)
			(property "Value" "LED_G_0603_LG_L29K-G2J1-24-Z"
				(at 20.32 -7.62 0)
				(effects
					(font
						(size 1.27 1.27)
						(thickness 0.15)
					)
					(justify left bottom)
					(hide yes)
				)
			)
			(property "Footprint" "antmicro-footprints:LED_0603_1608Metric_G"
				(at 20.32 -10.16 0)
				(effects
					(font
						(size 1.27 1.27)
						(thickness 0.15)
					)
					(justify left bottom)
					(hide yes)
				)
			)
			(property "Datasheet" "https://look.ams-osram.com/m/19ee86b3ae0ee95b/original/LG-L29K.pdf"
				(at 20.32 -12.7 0)
				(effects
					(font
						(size 1.27 1.27)
						(thickness 0.15)
					)
					(justify left bottom)
					(hide yes)
				)
			)
			(property "Description" "LED, Green, SMD, 0603, 20 mA, 1.7 V, 570 nm"
				(at 20.32 -25.4 0)
				(effects
					(font
						(size 1.27 1.27)
					)
					(justify left bottom)
					(hide yes)
				)
			)
			(property "MPN" "LG L29K-G2J1-24-Z"
				(at 20.32 -15.24 0)
				(effects
					(font
						(size 1.27 1.27)
						(thickness 0.15)
					)
					(justify left bottom)
					(hide yes)
				)
			)
			(property "Manufacturer" "OSRAM"
				(at 20.32 -17.78 0)
				(effects
					(font
						(size 1.27 1.27)
						(thickness 0.15)
					)
					(justify left bottom)
					(hide yes)
				)
			)
			(property "Color" "Green"
				(at 20.32 -5.08 0)
				(effects
					(font
						(size 1.27 1.27)
					)
					(justify left bottom)
				)
			)
			(property "Author" "Antmicro"
				(at 20.32 -20.32 0)
				(effects
					(font
						(size 1.27 1.27)
						(thickness 0.15)
					)
					(justify left bottom)
					(hide yes)
				)
			)
			(property "License" "Apache-2.0"
				(at 20.32 -22.86 0)
				(effects
					(font
						(size 1.27 1.27)
						(thickness 0.15)
					)
					(justify left bottom)
					(hide yes)
				)
			)
			(property "ki_keywords" "SMT, DIODE, SEMICONDUCTOR, LED"
				(at 0 0 0)
				(effects
					(font
						(size 1.27 1.27)
					)
					(hide yes)
				)
			)
			(symbol "LED_G_0603_LG_L29K-G2J1-24-Z_0_1"
				(polyline
					(pts
						(xy 1.905 0) (xy 0.635 0)
					)
					(stroke
						(width 0)
						(type default)
					)
					(fill
						(type none)
					)
				)
				(polyline
					(pts
						(xy 4.445 0) (xy 3.175 0)
					)
					(stroke
						(width 0)
						(type default)
					)
					(fill
						(type none)
					)
				)
			)
			(symbol "LED_G_0603_LG_L29K-G2J1-24-Z_1_1"
				(polyline
					(pts
						(xy 1.143 2.286) (xy 1.143 1.778) (xy 1.143 2.286) (xy 1.651 2.286) (xy 1.143 2.286) (xy 2.159 1.27)
					)
					(stroke
						(width 0.254)
						(type default)
					)
					(fill
						(type none)
					)
				)
				(polyline
					(pts
						(xy 1.778 1.016) (xy 1.778 -1.016)
					)
					(stroke
						(width 0.254)
						(type default)
					)
					(fill
						(type none)
					)
				)
				(polyline
					(pts
						(xy 2.159 2.54) (xy 2.159 2.032) (xy 2.159 2.54) (xy 2.667 2.54) (xy 2.159 2.54) (xy 3.048 1.651)
					)
					(stroke
						(width 0.254)
						(type default)
					)
					(fill
						(type none)
					)
				)
				(polyline
					(pts
						(xy 3.302 1.016) (xy 3.302 -1.016) (xy 1.778 0) (xy 3.302 1.016)
					)
					(stroke
						(width 0.254)
						(type default)
					)
					(fill
						(type outline)
					)
				)
				(pin passive line
					(at 0 0 0)
					(length 0.635)
					(name "C"
						(effects
							(font
								(size 1.27 1.27)
							)
						)
					)
					(number "1"
						(effects
							(font
								(size 1.27 1.27)
							)
						)
					)
				)
				(pin passive line
					(at 5.08 0 180)
					(length 0.635)
					(name "A"
						(effects
							(font
								(size 1.27 1.27)
							)
						)
					)
					(number "2"
						(effects
							(font
								(size 1.27 1.27)
							)
						)
					)
				)
			)
		)
	(symbol "antmicroLogicBuffersDriversReceiversTransceivers:74LVC1G07_SOT-753"
			(exclude_from_sim no)
			(in_bom yes)
			(on_board yes)
			(property "Reference" "U"
				(at 30.48 2.54 0)
				(effects
					(font
						(size 1.27 1.27)
						(thickness 0.15)
					)
					(justify left bottom)
				)
			)
			(property "Value" "74LVC1G07_SOT-753"
				(at 30.48 0 0)
				(effects
					(font
						(size 1.27 1.27)
						(thickness 0.15)
					)
					(justify left bottom)
					(hide yes)
				)
			)
			(property "Footprint" "antmicro-footprints:SOT-753"
				(at 30.48 -2.54 0)
				(effects
					(font
						(size 1.27 1.27)
						(thickness 0.15)
					)
					(justify left bottom)
					(hide yes)
				)
			)
			(property "Datasheet" "https://www.mouser.com/datasheet/2/916/74LVC1G07-1529858.pdf"
				(at 30.48 -5.08 0)
				(effects
					(font
						(size 1.27 1.27)
						(thickness 0.15)
					)
					(justify left bottom)
					(hide yes)
				)
			)
			(property "Description" "Buffer, 74LVC1G07, 1.65 V to 5.5 V, SC-74A-5"
				(at 30.48 -17.78 0)
				(effects
					(font
						(size 1.27 1.27)
					)
					(justify left bottom)
					(hide yes)
				)
			)
			(property "MPN" "74LVC1G07GV,125"
				(at 30.48 -7.62 0)
				(effects
					(font
						(size 1.27 1.27)
						(thickness 0.15)
					)
					(justify left bottom)
				)
			)
			(property "Manufacturer" "Nexperia"
				(at 30.48 -10.16 0)
				(effects
					(font
						(size 1.27 1.27)
						(thickness 0.15)
					)
					(justify left bottom)
					(hide yes)
				)
			)
			(property "Author" "Antmicro"
				(at 30.48 -12.7 0)
				(effects
					(font
						(size 1.27 1.27)
						(thickness 0.15)
					)
					(justify left bottom)
					(hide yes)
				)
			)
			(property "License" "Apache-2.0"
				(at 30.48 -15.24 0)
				(effects
					(font
						(size 1.27 1.27)
						(thickness 0.15)
					)
					(justify left bottom)
					(hide yes)
				)
			)
			(property "ki_keywords" "BUFFER"
				(at 0 0 0)
				(effects
					(font
						(size 1.27 1.27)
					)
					(hide yes)
				)
			)
			(symbol "74LVC1G07_SOT-753_1_1"
				(rectangle
					(start 2.54 2.54)
					(end 15.24 -8.89)
					(stroke
						(width 0.254)
						(type default)
					)
					(fill
						(type background)
					)
				)
				(polyline
					(pts
						(xy 6.35 -1.27) (xy 6.35 -6.35) (xy 11.43 -3.81) (xy 6.35 -1.27)
					)
					(stroke
						(width 0.254)
						(type default)
					)
					(fill
						(type background)
					)
				)
				(polyline
					(pts
						(xy 6.35 -3.81) (xy 5.08 -3.81)
					)
					(stroke
						(width 0.254)
						(type default)
					)
					(fill
						(type background)
					)
				)
				(polyline
					(pts
						(xy 6.985 -4.445) (xy 8.255 -4.445)
					)
					(stroke
						(width 0.254)
						(type default)
					)
					(fill
						(type background)
					)
				)
				(polyline
					(pts
						(xy 7.62 -3.175) (xy 6.985 -3.81) (xy 7.62 -4.445) (xy 8.255 -3.81) (xy 7.62 -3.175)
					)
					(stroke
						(width 0.254)
						(type default)
					)
					(fill
						(type background)
					)
				)
				(polyline
					(pts
						(xy 11.43 -3.81) (xy 12.7 -3.81)
					)
					(stroke
						(width 0.254)
						(type default)
					)
					(fill
						(type background)
					)
				)
				(pin power_in line
					(at 0 0 0)
					(length 2.54)
					(name "VCC"
						(effects
							(font
								(size 1.27 1.27)
							)
						)
					)
					(number "5"
						(effects
							(font
								(size 1.27 1.27)
							)
						)
					)
				)
				(pin input line
					(at 0 -3.81 0)
					(length 2.54)
					(name "A"
						(effects
							(font
								(size 1.27 1.27)
							)
						)
					)
					(number "2"
						(effects
							(font
								(size 1.27 1.27)
							)
						)
					)
				)
				(pin no_connect line
					(at 2.54 -6.35 0)
					(length 2.54)
					(hide yes)
					(name "NC"
						(effects
							(font
								(size 1.27 1.27)
							)
						)
					)
					(number "1"
						(effects
							(font
								(size 1.27 1.27)
							)
						)
					)
				)
				(pin output line
					(at 17.78 -3.81 180)
					(length 2.54)
					(name "Y"
						(effects
							(font
								(size 1.27 1.27)
							)
						)
					)
					(number "4"
						(effects
							(font
								(size 1.27 1.27)
							)
						)
					)
				)
				(pin power_in line
					(at 17.78 -6.35 180)
					(length 2.54)
					(name "GND"
						(effects
							(font
								(size 1.27 1.27)
							)
						)
					)
					(number "3"
						(effects
							(font
								(size 1.27 1.27)
							)
						)
					)
				)
			)
		)
	(symbol "antmicroLogicTranslatorsLevelShifters:NTS0102_TSSOP"
			(exclude_from_sim no)
			(in_bom yes)
			(on_board yes)
			(property "Reference" "U"
				(at 35.56 -3.81 0)
				(effects
					(font
						(size 1.27 1.27)
						(thickness 0.15)
					)
					(justify left bottom)
				)
			)
			(property "Value" "NTS0102_TSSOP"
				(at 35.56 -6.35 0)
				(effects
					(font
						(size 1.27 1.27)
						(thickness 0.15)
					)
					(justify left bottom)
					(hide yes)
				)
			)
			(property "Footprint" "antmicro-footprints:TSSOP-8_3x3mm_P0.65mm"
				(at 35.56 -8.89 0)
				(effects
					(font
						(size 1.27 1.27)
						(thickness 0.15)
					)
					(justify left bottom)
					(hide yes)
				)
			)
			(property "Datasheet" "https://www.mouser.com/datasheet/2/302/NTS0102-1127324.pdf"
				(at 35.56 -11.43 0)
				(effects
					(font
						(size 1.27 1.27)
						(thickness 0.15)
					)
					(justify left bottom)
					(hide yes)
				)
			)
			(property "Description" "Transceiver, 1.65 V to 3.6 V, TSSOP-8"
				(at 35.56 -24.13 0)
				(effects
					(font
						(size 1.27 1.27)
					)
					(justify left bottom)
					(hide yes)
				)
			)
			(property "MPN" "NTS0102DP"
				(at 35.56 -13.97 0)
				(effects
					(font
						(size 1.27 1.27)
						(thickness 0.15)
					)
					(justify left bottom)
				)
			)
			(property "Manufacturer" "NXP"
				(at 35.56 -16.51 0)
				(effects
					(font
						(size 1.27 1.27)
						(thickness 0.15)
					)
					(justify left bottom)
					(hide yes)
				)
			)
			(property "Author" "Antmicro"
				(at 35.56 -19.05 0)
				(effects
					(font
						(size 1.27 1.27)
						(thickness 0.15)
					)
					(justify left bottom)
					(hide yes)
				)
			)
			(property "License" "Apache-2.0"
				(at 35.56 -21.59 0)
				(effects
					(font
						(size 1.27 1.27)
						(thickness 0.15)
					)
					(justify left bottom)
					(hide yes)
				)
			)
			(property "ki_keywords" "SMT, LEVEL-SHIFTER, IC, LOGIC"
				(at 0 0 0)
				(effects
					(font
						(size 1.27 1.27)
					)
					(hide yes)
				)
			)
			(symbol "NTS0102_TSSOP_1_1"
				(rectangle
					(start 2.54 2.54)
					(end 17.78 -10.16)
					(stroke
						(width 0.254)
						(type default)
					)
					(fill
						(type background)
					)
				)
				(pin power_in line
					(at 0 0 0)
					(length 2.54)
					(name "VCC_{A}"
						(effects
							(font
								(size 1.27 1.27)
							)
						)
					)
					(number "3"
						(effects
							(font
								(size 1.27 1.27)
							)
						)
					)
				)
				(pin bidirectional line
					(at 0 -2.54 0)
					(length 2.54)
					(name "A_{1}"
						(effects
							(font
								(size 1.27 1.27)
							)
						)
					)
					(number "5"
						(effects
							(font
								(size 1.27 1.27)
							)
						)
					)
				)
				(pin bidirectional line
					(at 0 -5.08 0)
					(length 2.54)
					(name "A_{2}"
						(effects
							(font
								(size 1.27 1.27)
							)
						)
					)
					(number "4"
						(effects
							(font
								(size 1.27 1.27)
							)
						)
					)
				)
				(pin input line
					(at 0 -7.62 0)
					(length 2.54)
					(name "OE"
						(effects
							(font
								(size 1.27 1.27)
							)
						)
					)
					(number "6"
						(effects
							(font
								(size 1.27 1.27)
							)
						)
					)
				)
				(pin power_in line
					(at 20.32 0 180)
					(length 2.54)
					(name "VCC_{B}"
						(effects
							(font
								(size 1.27 1.27)
							)
						)
					)
					(number "7"
						(effects
							(font
								(size 1.27 1.27)
							)
						)
					)
				)
				(pin bidirectional line
					(at 20.32 -2.54 180)
					(length 2.54)
					(name "B_{1}"
						(effects
							(font
								(size 1.27 1.27)
							)
						)
					)
					(number "8"
						(effects
							(font
								(size 1.27 1.27)
							)
						)
					)
				)
				(pin bidirectional line
					(at 20.32 -5.08 180)
					(length 2.54)
					(name "B_{2}"
						(effects
							(font
								(size 1.27 1.27)
							)
						)
					)
					(number "1"
						(effects
							(font
								(size 1.27 1.27)
							)
						)
					)
				)
				(pin power_in line
					(at 20.32 -7.62 180)
					(length 2.54)
					(name "GND"
						(effects
							(font
								(size 1.27 1.27)
							)
						)
					)
					(number "2"
						(effects
							(font
								(size 1.27 1.27)
							)
						)
					)
				)
			)
		)
	(symbol "antmicroMechanicalParts:Heatsink_ATS-61500R-C2-R0"
			(pin_names
				(hide yes)
			)
			(exclude_from_sim no)
			(in_bom yes)
			(on_board yes)
			(property "Reference" "H"
				(at 17.78 -2.54 0)
				(effects
					(font
						(size 1.27 1.27)
						(thickness 0.15)
					)
					(justify left bottom)
				)
			)
			(property "Value" "Heatsink_ATS-61500R-C2-R0"
				(at 17.78 -5.08 0)
				(effects
					(font
						(size 1.27 1.27)
						(thickness 0.15)
					)
					(justify left bottom)
					(hide yes)
				)
			)
			(property "Footprint" "antmicro-footprints:Heatsink_ATS-61500R-C2-R0"
				(at 17.78 -7.62 0)
				(effects
					(font
						(size 1.27 1.27)
						(thickness 0.15)
					)
					(justify left bottom)
					(hide yes)
				)
			)
			(property "Datasheet" "https://www.qats.com/DataSheet/ATS-61500-Series-C2-R0"
				(at 17.78 -10.16 0)
				(effects
					(font
						(size 1.27 1.27)
						(thickness 0.15)
					)
					(justify left bottom)
					(hide yes)
				)
			)
			(property "Description" "Heat Sinks fanSINK Assembly with Mounting Hardware"
				(at 17.78 -22.86 0)
				(effects
					(font
						(size 1.27 1.27)
					)
					(justify left bottom)
					(hide yes)
				)
			)
			(property "MPN" "ATS-61500R-C2-R0"
				(at 17.78 -12.7 0)
				(effects
					(font
						(size 1.27 1.27)
						(thickness 0.15)
					)
					(justify left bottom)
				)
			)
			(property "Manufacturer" "Advanced Thermal Solutions"
				(at 17.78 -15.24 0)
				(effects
					(font
						(size 1.27 1.27)
						(thickness 0.15)
					)
					(justify left bottom)
					(hide yes)
				)
			)
			(property "Author" "Antmicro"
				(at 17.78 -17.78 0)
				(effects
					(font
						(size 1.27 1.27)
						(thickness 0.15)
					)
					(justify left bottom)
					(hide yes)
				)
			)
			(property "License" "Apache-2.0"
				(at 17.78 -20.32 0)
				(effects
					(font
						(size 1.27 1.27)
						(thickness 0.15)
					)
					(justify left bottom)
					(hide yes)
				)
			)
			(property "ki_keywords" "HEATSINK"
				(at 0 0 0)
				(effects
					(font
						(size 1.27 1.27)
					)
					(hide yes)
				)
			)
			(property "ki_fp_filters" "Heatsink_*"
				(at 0 0 0)
				(effects
					(font
						(size 1.27 1.27)
					)
					(hide yes)
				)
			)
			(symbol "Heatsink_ATS-61500R-C2-R0_0_1"
				(polyline
					(pts
						(xy 0 0) (xy 0.635 0) (xy 0.635 -3.175) (xy 1.27 -3.175) (xy 1.27 0) (xy 1.905 0) (xy 1.905 -3.175)
						(xy 2.54 -3.175) (xy 2.54 0) (xy 3.175 0) (xy 3.175 -3.175) (xy 3.81 -3.175) (xy 3.81 0) (xy 4.445 0)
						(xy 4.445 -3.175) (xy 5.08 -3.175) (xy 5.08 0) (xy 5.715 0) (xy 5.715 -4.445) (xy 0 -4.445) (xy 0 0)
					)
					(stroke
						(width 0)
						(type default)
					)
					(fill
						(type background)
					)
				)
			)
		)
	(symbol "antmicroMechanicalParts:MP_Pad6mm_Drill3.2mm"
			(pin_names
				(hide yes)
			)
			(exclude_from_sim no)
			(in_bom no)
			(on_board yes)
			(property "Reference" "MP"
				(at 20.32 -2.54 0)
				(effects
					(font
						(size 1.27 1.27)
						(thickness 0.15)
					)
					(justify left bottom)
				)
			)
			(property "Value" "MP_Pad6mm_Drill3.2mm"
				(at 20.32 -5.08 0)
				(effects
					(font
						(size 1.27 1.27)
						(thickness 0.15)
					)
					(justify left bottom)
				)
			)
			(property "Footprint" "antmicro-footprints:MP_Pad6mm_Drill3.2mm"
				(at 20.32 -7.62 0)
				(effects
					(font
						(size 1.27 1.27)
						(thickness 0.15)
					)
					(justify left bottom)
					(hide yes)
				)
			)
			(property "Datasheet" ""
				(at 16.84 -15.57 0)
				(effects
					(font
						(size 1.27 1.27)
						(thickness 0.15)
					)
					(justify left bottom)
					(hide yes)
				)
			)
			(property "Description" "Mechanical part"
				(at 20.32 -15.24 0)
				(effects
					(font
						(size 1.27 1.27)
					)
					(justify left bottom)
					(hide yes)
				)
			)
			(property "Author" "Antmicro"
				(at 20.32 -10.16 0)
				(effects
					(font
						(size 1.27 1.27)
						(thickness 0.15)
					)
					(justify left bottom)
					(hide yes)
				)
			)
			(property "License" "Apache-2.0"
				(at 20.32 -12.7 0)
				(effects
					(font
						(size 1.27 1.27)
						(thickness 0.15)
					)
					(justify left bottom)
					(hide yes)
				)
			)
			(property "ki_keywords" "MECHANICAL"
				(at 0 0 0)
				(effects
					(font
						(size 1.27 1.27)
					)
					(hide yes)
				)
			)
			(symbol "MP_Pad6mm_Drill3.2mm_1_1"
				(circle
					(center 5.08 0)
					(radius 1.27)
					(stroke
						(width 0.254)
						(type default)
					)
					(fill
						(type background)
					)
				)
				(circle
					(center 5.08 0)
					(radius 2.54)
					(stroke
						(width 0.254)
						(type default)
					)
					(fill
						(type background)
					)
				)
				(pin passive line
					(at 0 0 0)
					(length 2.54)
					(name "~"
						(effects
							(font
								(size 1.27 1.27)
							)
						)
					)
					(number "1"
						(effects
							(font
								(size 1.27 1.27)
							)
						)
					)
				)
			)
		)
	(symbol "antmicroMechanicalParts:MP_Terminal_M3_THT_7760"
			(exclude_from_sim no)
			(in_bom yes)
			(on_board yes)
			(property "Reference" "J"
				(at 22.86 -2.54 0)
				(effects
					(font
						(size 1.27 1.27)
						(thickness 0.15)
					)
					(justify left bottom)
				)
			)
			(property "Value" "MP_Terminal_M3_THT_7760"
				(at 22.86 -7.62 0)
				(effects
					(font
						(size 1.27 1.27)
						(thickness 0.15)
					)
					(justify left bottom)
					(hide yes)
				)
			)
			(property "Footprint" "antmicro-footprints:MP_Terminal_M3_THT_7760"
				(at 22.86 -10.16 0)
				(effects
					(font
						(size 1.27 1.27)
						(thickness 0.15)
					)
					(justify left bottom)
					(hide yes)
				)
			)
			(property "Datasheet" "https://www.mouser.com/datasheet/2/215/7760-741244.pdf"
				(at 22.86 -12.7 0)
				(effects
					(font
						(size 1.27 1.27)
						(thickness 0.15)
					)
					(justify left bottom)
					(hide yes)
				)
			)
			(property "Description" "PCB Terminal, 90° THT, Brass, Tin"
				(at 22.86 -25.4 0)
				(effects
					(font
						(size 1.27 1.27)
						(thickness 0.15)
					)
					(justify left bottom)
					(hide yes)
				)
			)
			(property "MPN" "7760"
				(at 22.86 -5.08 0)
				(effects
					(font
						(size 1.27 1.27)
						(thickness 0.15)
					)
					(justify left bottom)
				)
			)
			(property "Manufacturer" "Keystone Electronics"
				(at 22.86 -17.78 0)
				(effects
					(font
						(size 1.27 1.27)
						(thickness 0.15)
					)
					(justify left bottom)
					(hide yes)
				)
			)
			(property "Author" "Antmicro"
				(at 22.86 -20.32 0)
				(effects
					(font
						(size 1.27 1.27)
						(thickness 0.15)
					)
					(justify left bottom)
					(hide yes)
				)
			)
			(property "License" "Apache-2.0"
				(at 22.86 -22.86 0)
				(effects
					(font
						(size 1.27 1.27)
						(thickness 0.15)
					)
					(justify left bottom)
					(hide yes)
				)
			)
			(property "ki_keywords" "HORIZONTAL, THT, CONNECTOR"
				(at 0 0 0)
				(effects
					(font
						(size 1.27 1.27)
					)
					(hide yes)
				)
			)
			(symbol "MP_Terminal_M3_THT_7760_1_1"
				(rectangle
					(start 2.54 -2.54)
					(end 7.62 2.54)
					(stroke
						(width 0.254)
						(type default)
					)
					(fill
						(type background)
					)
				)
				(circle
					(center 5.08 0)
					(radius 1.27)
					(stroke
						(width 0.254)
						(type default)
					)
					(fill
						(type background)
					)
				)
				(pin passive line
					(at 0 0 0)
					(length 2.54)
					(name "~"
						(effects
							(font
								(size 1.27 1.27)
							)
						)
					)
					(number "1"
						(effects
							(font
								(size 1.27 1.27)
							)
						)
					)
				)
			)
		)
	(symbol "antmicroMemory:AT25DF641A-SH"
			(exclude_from_sim no)
			(in_bom yes)
			(on_board yes)
			(property "Reference" "U"
				(at 33.02 -2.54 0)
				(effects
					(font
						(size 1.27 1.27)
						(thickness 0.15)
					)
					(justify left bottom)
				)
			)
			(property "Value" "AT25DF641A-SH"
				(at 33.02 -7.62 0)
				(effects
					(font
						(size 1.27 1.27)
						(thickness 0.15)
					)
					(justify left bottom)
					(hide yes)
				)
			)
			(property "Footprint" "antmicro-footprints:SOIC-8_5.3x5.3x2mm_P1.27mm"
				(at 33.02 -10.16 0)
				(effects
					(font
						(size 1.27 1.27)
						(thickness 0.15)
					)
					(justify left bottom)
					(hide yes)
				)
			)
			(property "Datasheet" "https://eu.mouser.com/datasheet/3/1166/1/REN_DS-AT25DF641A-8693G-022022_unsecure_DST_20220220_1.pdf"
				(at 33.02 -12.7 0)
				(effects
					(font
						(size 1.27 1.27)
						(thickness 0.15)
					)
					(justify left bottom)
					(hide yes)
				)
			)
			(property "Description" "NOR Flash 64 Mbit, 3.0V (2.7V to 3.6V), -40C to 85C, SOIC-W 208mil (Tape & Reel), Single, Dual SPI NOR flash"
				(at 33.02 -15.24 0)
				(effects
					(font
						(size 1.27 1.27)
						(thickness 0.15)
					)
					(justify left bottom)
					(hide yes)
				)
			)
			(property "MPN" "AT25DF641A-SH-T "
				(at 33.02 -5.08 0)
				(effects
					(font
						(size 1.27 1.27)
						(thickness 0.15)
					)
					(justify left bottom)
				)
			)
			(property "Manufacturer" "Renesas"
				(at 33.02 -17.78 0)
				(effects
					(font
						(size 1.27 1.27)
						(thickness 0.15)
					)
					(justify left bottom)
					(hide yes)
				)
			)
			(property "Author" "Antmicro"
				(at 33.02 -20.32 0)
				(effects
					(font
						(size 1.27 1.27)
						(thickness 0.15)
					)
					(justify left bottom)
					(hide yes)
				)
			)
			(property "License" "Apache-2.0"
				(at 33.02 -22.86 0)
				(effects
					(font
						(size 1.27 1.27)
						(thickness 0.15)
					)
					(justify left bottom)
					(hide yes)
				)
			)
			(property "ki_keywords" "FLASH, SPI, MEMORY"
				(at 0 0 0)
				(effects
					(font
						(size 1.27 1.27)
					)
					(hide yes)
				)
			)
			(symbol "AT25DF641A-SH_1_1"
				(rectangle
					(start 2.54 2.54)
					(end 16.51 -15.24)
					(stroke
						(width 0.254)
						(type default)
					)
					(fill
						(type background)
					)
				)
				(pin bidirectional line
					(at 0 0 0)
					(length 2.54)
					(name "SI"
						(effects
							(font
								(size 1.27 1.27)
							)
						)
					)
					(number "5"
						(effects
							(font
								(size 1.27 1.27)
							)
						)
					)
				)
				(pin bidirectional line
					(at 0 -2.54 0)
					(length 2.54)
					(name "SO"
						(effects
							(font
								(size 1.27 1.27)
							)
						)
					)
					(number "2"
						(effects
							(font
								(size 1.27 1.27)
							)
						)
					)
				)
				(pin bidirectional line
					(at 0 -5.08 0)
					(length 2.54)
					(name "~{WP}"
						(effects
							(font
								(size 1.27 1.27)
							)
						)
					)
					(number "3"
						(effects
							(font
								(size 1.27 1.27)
							)
						)
					)
				)
				(pin bidirectional line
					(at 0 -7.62 0)
					(length 2.54)
					(name "~{HOLD}"
						(effects
							(font
								(size 1.27 1.27)
							)
						)
					)
					(number "7"
						(effects
							(font
								(size 1.27 1.27)
							)
						)
					)
				)
				(pin input line
					(at 0 -10.16 0)
					(length 2.54)
					(name "SCK"
						(effects
							(font
								(size 1.27 1.27)
							)
						)
					)
					(number "6"
						(effects
							(font
								(size 1.27 1.27)
							)
						)
					)
				)
				(pin input line
					(at 0 -12.7 0)
					(length 2.54)
					(name "~{CS}"
						(effects
							(font
								(size 1.27 1.27)
							)
						)
					)
					(number "1"
						(effects
							(font
								(size 1.27 1.27)
							)
						)
					)
				)
				(pin power_in line
					(at 19.05 0 180)
					(length 2.54)
					(name "VCC"
						(effects
							(font
								(size 1.27 1.27)
							)
						)
					)
					(number "8"
						(effects
							(font
								(size 1.27 1.27)
							)
						)
					)
				)
				(pin power_in line
					(at 19.05 -12.7 180)
					(length 2.54)
					(name "GND"
						(effects
							(font
								(size 1.27 1.27)
							)
						)
					)
					(number "4"
						(effects
							(font
								(size 1.27 1.27)
							)
						)
					)
				)
			)
		)
	(symbol "antmicroModularConnectorsJacksWithMagnetics:Bus_RJ45_JTH-0024NL"
			(exclude_from_sim no)
			(in_bom yes)
			(on_board yes)
			(property "Reference" "J"
				(at 35.56 -2.54 0)
				(effects
					(font
						(size 1.27 1.27)
						(thickness 0.15)
					)
					(justify left bottom)
				)
			)
			(property "Value" "Bus_RJ45_JTH-0024NL"
				(at 35.56 -5.08 0)
				(effects
					(font
						(size 1.27 1.27)
						(thickness 0.15)
					)
					(justify left bottom)
					(hide yes)
				)
			)
			(property "Footprint" "antmicro-footprints:RJ45_JTH-0024NL"
				(at 35.56 -7.62 0)
				(effects
					(font
						(size 1.27 1.27)
						(thickness 0.15)
					)
					(justify left bottom)
					(hide yes)
				)
			)
			(property "Datasheet" "https://www.mouser.com/datasheet/2/447/JTH_0024NL-3072047.pdf"
				(at 35.56 -10.16 0)
				(effects
					(font
						(size 1.27 1.27)
						(thickness 0.15)
					)
					(justify left bottom)
					(hide yes)
				)
			)
			(property "Description" "Modular Connectors / Ethernet Connectors 1X1 TAB DOWN W/LED'S ETHERNET (NON PoE)"
				(at 35.56 -22.86 0)
				(effects
					(font
						(size 1.27 1.27)
					)
					(justify left bottom)
					(hide yes)
				)
			)
			(property "MPN" "JTH-0024NL"
				(at 35.56 -12.7 0)
				(effects
					(font
						(size 1.27 1.27)
						(thickness 0.15)
					)
					(justify left bottom)
				)
			)
			(property "Manufacturer" "Pulse Electronics"
				(at 35.56 -15.24 0)
				(effects
					(font
						(size 1.27 1.27)
						(thickness 0.15)
					)
					(justify left bottom)
					(hide yes)
				)
			)
			(property "Author" "Antmicro"
				(at 35.56 -17.78 0)
				(effects
					(font
						(size 1.27 1.27)
						(thickness 0.15)
					)
					(justify left bottom)
					(hide yes)
				)
			)
			(property "License" "Apache-2.0"
				(at 35.56 -20.32 0)
				(effects
					(font
						(size 1.27 1.27)
						(thickness 0.15)
					)
					(justify left bottom)
					(hide yes)
				)
			)
			(property "ki_keywords" "RJ45, HORIZONTAL, THT, ETHERNET, CONNECTOR, FEMALE"
				(at 0 0 0)
				(effects
					(font
						(size 1.27 1.27)
					)
					(hide yes)
				)
			)
			(property "ki_fp_filters" "CONN18_5-2337992-8_TEC"
				(at 0 0 0)
				(effects
					(font
						(size 1.27 1.27)
					)
					(hide yes)
				)
			)
			(symbol "Bus_RJ45_JTH-0024NL_1_1"
				(rectangle
					(start 2.54 2.54)
					(end 19.05 -38.1)
					(stroke
						(width 0.254)
						(type default)
					)
					(fill
						(type background)
					)
				)
				(polyline
					(pts
						(xy 8.89 -1.27) (xy 8.89 -13.97)
					)
					(stroke
						(width 0.254)
						(type default)
					)
					(fill
						(type background)
					)
				)
				(polyline
					(pts
						(xy 8.89 -1.27) (xy 13.97 -1.27)
					)
					(stroke
						(width 0.254)
						(type default)
					)
					(fill
						(type background)
					)
				)
				(polyline
					(pts
						(xy 8.89 -13.97) (xy 13.97 -13.97)
					)
					(stroke
						(width 0.254)
						(type default)
					)
					(fill
						(type background)
					)
				)
				(polyline
					(pts
						(xy 13.97 -1.27) (xy 13.97 -2.54)
					)
					(stroke
						(width 0.254)
						(type default)
					)
					(fill
						(type background)
					)
				)
				(polyline
					(pts
						(xy 13.97 -2.54) (xy 15.24 -2.54)
					)
					(stroke
						(width 0.254)
						(type default)
					)
					(fill
						(type background)
					)
				)
				(polyline
					(pts
						(xy 13.97 -12.7) (xy 15.24 -12.7)
					)
					(stroke
						(width 0.254)
						(type default)
					)
					(fill
						(type background)
					)
				)
				(polyline
					(pts
						(xy 13.97 -13.97) (xy 13.97 -12.7)
					)
					(stroke
						(width 0.254)
						(type default)
					)
					(fill
						(type background)
					)
				)
				(polyline
					(pts
						(xy 15.24 -2.54) (xy 15.24 -3.81)
					)
					(stroke
						(width 0.254)
						(type default)
					)
					(fill
						(type background)
					)
				)
				(polyline
					(pts
						(xy 15.24 -3.81) (xy 16.51 -3.81)
					)
					(stroke
						(width 0.254)
						(type default)
					)
					(fill
						(type background)
					)
				)
				(polyline
					(pts
						(xy 15.24 -11.43) (xy 16.51 -11.43)
					)
					(stroke
						(width 0.254)
						(type default)
					)
					(fill
						(type background)
					)
				)
				(polyline
					(pts
						(xy 15.24 -12.7) (xy 15.24 -11.43)
					)
					(stroke
						(width 0.254)
						(type default)
					)
					(fill
						(type background)
					)
				)
				(polyline
					(pts
						(xy 16.51 -3.81) (xy 16.51 -11.43)
					)
					(stroke
						(width 0.254)
						(type default)
					)
					(fill
						(type background)
					)
				)
				(pin bidirectional line
					(at 0 0 0)
					(length 2.54)
					(name "T1+"
						(effects
							(font
								(size 1.27 1.27)
							)
						)
					)
					(number "8"
						(effects
							(font
								(size 1.27 1.27)
							)
						)
					)
				)
				(pin bidirectional line
					(at 0 -2.54 0)
					(length 2.54)
					(name "T1-"
						(effects
							(font
								(size 1.27 1.27)
							)
						)
					)
					(number "9"
						(effects
							(font
								(size 1.27 1.27)
							)
						)
					)
				)
				(pin bidirectional line
					(at 0 -5.08 0)
					(length 2.54)
					(name "T2+"
						(effects
							(font
								(size 1.27 1.27)
							)
						)
					)
					(number "3"
						(effects
							(font
								(size 1.27 1.27)
							)
						)
					)
				)
				(pin bidirectional line
					(at 0 -7.62 0)
					(length 2.54)
					(name "T2-"
						(effects
							(font
								(size 1.27 1.27)
							)
						)
					)
					(number "2"
						(effects
							(font
								(size 1.27 1.27)
							)
						)
					)
				)
				(pin bidirectional line
					(at 0 -10.16 0)
					(length 2.54)
					(name "T3+"
						(effects
							(font
								(size 1.27 1.27)
							)
						)
					)
					(number "4"
						(effects
							(font
								(size 1.27 1.27)
							)
						)
					)
				)
				(pin bidirectional line
					(at 0 -12.7 0)
					(length 2.54)
					(name "T3-"
						(effects
							(font
								(size 1.27 1.27)
							)
						)
					)
					(number "5"
						(effects
							(font
								(size 1.27 1.27)
							)
						)
					)
				)
				(pin bidirectional line
					(at 0 -15.24 0)
					(length 2.54)
					(name "T4+"
						(effects
							(font
								(size 1.27 1.27)
							)
						)
					)
					(number "11"
						(effects
							(font
								(size 1.27 1.27)
							)
						)
					)
				)
				(pin bidirectional line
					(at 0 -17.78 0)
					(length 2.54)
					(name "T4-"
						(effects
							(font
								(size 1.27 1.27)
							)
						)
					)
					(number "10"
						(effects
							(font
								(size 1.27 1.27)
							)
						)
					)
				)
				(pin bidirectional line
					(at 0 -27.94 0)
					(length 2.54)
					(name "CT1"
						(effects
							(font
								(size 1.27 1.27)
							)
						)
					)
					(number "12"
						(effects
							(font
								(size 1.27 1.27)
							)
						)
					)
				)
				(pin bidirectional line
					(at 0 -30.48 0)
					(length 2.54)
					(name "CT2"
						(effects
							(font
								(size 1.27 1.27)
							)
						)
					)
					(number "6"
						(effects
							(font
								(size 1.27 1.27)
							)
						)
					)
				)
				(pin bidirectional line
					(at 0 -33.02 0)
					(length 2.54)
					(name "CT3"
						(effects
							(font
								(size 1.27 1.27)
							)
						)
					)
					(number "1"
						(effects
							(font
								(size 1.27 1.27)
							)
						)
					)
				)
				(pin bidirectional line
					(at 0 -35.56 0)
					(length 2.54)
					(name "CT4"
						(effects
							(font
								(size 1.27 1.27)
							)
						)
					)
					(number "7"
						(effects
							(font
								(size 1.27 1.27)
							)
						)
					)
				)
				(pin passive line
					(at 21.59 -17.78 180)
					(length 2.54)
					(name "LED_COM+"
						(effects
							(font
								(size 1.27 1.27)
							)
						)
					)
					(number "16"
						(effects
							(font
								(size 1.27 1.27)
							)
						)
					)
				)
				(pin passive line
					(at 21.59 -20.32 180)
					(length 2.54)
					(name "LED_YG_Y-"
						(effects
							(font
								(size 1.27 1.27)
							)
						)
					)
					(number "15"
						(effects
							(font
								(size 1.27 1.27)
							)
						)
					)
				)
				(pin passive line
					(at 21.59 -22.86 180)
					(length 2.54)
					(name "LED_YG_G-"
						(effects
							(font
								(size 1.27 1.27)
							)
						)
					)
					(number "17"
						(effects
							(font
								(size 1.27 1.27)
							)
						)
					)
				)
				(pin passive line
					(at 21.59 -27.94 180)
					(length 2.54)
					(name "LED_GRN+"
						(effects
							(font
								(size 1.27 1.27)
							)
						)
					)
					(number "14"
						(effects
							(font
								(size 1.27 1.27)
							)
						)
					)
				)
				(pin passive line
					(at 21.59 -30.48 180)
					(length 2.54)
					(name "LED_GRN-"
						(effects
							(font
								(size 1.27 1.27)
							)
						)
					)
					(number "13"
						(effects
							(font
								(size 1.27 1.27)
							)
						)
					)
				)
				(pin passive line
					(at 21.59 -35.56 180)
					(length 2.54)
					(name "SHIELD"
						(effects
							(font
								(size 1.27 1.27)
							)
						)
					)
					(number "SH"
						(effects
							(font
								(size 1.27 1.27)
							)
						)
					)
				)
			)
		)
	(symbol "antmicroOscillators:Oscillator_100MHz_NX324"
			(exclude_from_sim no)
			(in_bom yes)
			(on_board yes)
			(property "Reference" "Y"
				(at 29.21 -1.905 0)
				(effects
					(font
						(size 1.27 1.27)
						(thickness 0.15)
					)
					(justify left bottom)
				)
			)
			(property "Value" "Oscillator_100MHz_NX324"
				(at 29.21 -12.065 0)
				(effects
					(font
						(size 1.27 1.27)
						(thickness 0.15)
					)
					(justify left bottom)
					(hide yes)
				)
			)
			(property "Footprint" "antmicro-footprints:Oscillator_SMD_Abracon_AX3_3.2x2.5x1mm"
				(at 29.21 -14.605 0)
				(effects
					(font
						(size 1.27 1.27)
						(thickness 0.15)
					)
					(justify left bottom)
					(hide yes)
				)
			)
			(property "Datasheet" "https://www.diodes.com/assets/Datasheets/NX324.pdf"
				(at 29.21 -17.145 0)
				(effects
					(font
						(size 1.27 1.27)
						(thickness 0.15)
					)
					(justify left bottom)
					(hide yes)
				)
			)
			(property "Description" "100 MHz XO (Standard) HCSL Oscillator 3.3V Enable/Disable 6-SMD, No Lead"
				(at 29.21 -24.765 0)
				(effects
					(font
						(size 1.27 1.27)
					)
					(justify left bottom)
					(hide yes)
				)
			)
			(property "Manufacturer" "Diodes Incorporated"
				(at 29.21 -4.445 0)
				(effects
					(font
						(size 1.27 1.27)
						(thickness 0.15)
					)
					(justify left bottom)
					(hide yes)
				)
			)
			(property "MPN" "NX3241E0100.000000"
				(at 29.21 -6.985 0)
				(effects
					(font
						(size 1.27 1.27)
						(thickness 0.15)
					)
					(justify left bottom)
				)
			)
			(property "Val" "100 MHz"
				(at 29.21 -9.525 0)
				(effects
					(font
						(size 1.27 1.27)
						(thickness 0.15)
					)
					(justify left bottom)
				)
			)
			(property "Author" "Antmicro"
				(at 29.21 -19.685 0)
				(effects
					(font
						(size 1.27 1.27)
						(thickness 0.15)
					)
					(justify left bottom)
					(hide yes)
				)
			)
			(property "License" "Apache-2.0"
				(at 29.21 -22.225 0)
				(effects
					(font
						(size 1.27 1.27)
						(thickness 0.15)
					)
					(justify left bottom)
					(hide yes)
				)
			)
			(property "ki_keywords" "OSCILLATOR"
				(at 0 0 0)
				(effects
					(font
						(size 1.27 1.27)
					)
					(hide yes)
				)
			)
			(symbol "Oscillator_100MHz_NX324_1_1"
				(rectangle
					(start 2.54 2.54)
					(end 16.51 -7.62)
					(stroke
						(width 0.254)
						(type default)
					)
					(fill
						(type background)
					)
				)
				(polyline
					(pts
						(xy 7.62 -1.27) (xy 8.255 -1.27) (xy 8.255 0) (xy 8.89 0) (xy 8.89 -1.27) (xy 9.525 -1.27) (xy 9.525 0)
						(xy 10.16 0) (xy 10.16 -1.27)
					)
					(stroke
						(width 0.254)
						(type default)
					)
					(fill
						(type background)
					)
				)
				(pin power_in line
					(at 0 0 0)
					(length 2.54)
					(name "VCC"
						(effects
							(font
								(size 1.27 1.27)
							)
						)
					)
					(number "6"
						(effects
							(font
								(size 1.27 1.27)
							)
						)
					)
				)
				(pin input line
					(at 0 -2.54 0)
					(length 2.54)
					(name "EN"
						(effects
							(font
								(size 1.27 1.27)
							)
						)
					)
					(number "1"
						(effects
							(font
								(size 1.27 1.27)
							)
						)
					)
				)
				(pin power_in line
					(at 0 -5.08 0)
					(length 2.54)
					(name "GND"
						(effects
							(font
								(size 1.27 1.27)
							)
						)
					)
					(number "3"
						(effects
							(font
								(size 1.27 1.27)
							)
						)
					)
				)
				(pin no_connect line
					(at 16.51 -5.08 180)
					(length 2.54)
					(hide yes)
					(name "NC"
						(effects
							(font
								(size 1.27 1.27)
							)
						)
					)
					(number "2"
						(effects
							(font
								(size 1.27 1.27)
							)
						)
					)
				)
				(pin output line
					(at 19.05 0 180)
					(length 2.54)
					(name "OUT+"
						(effects
							(font
								(size 1.27 1.27)
							)
						)
					)
					(number "4"
						(effects
							(font
								(size 1.27 1.27)
							)
						)
					)
				)
				(pin output line
					(at 19.05 -2.54 180)
					(length 2.54)
					(name "OUT-"
						(effects
							(font
								(size 1.27 1.27)
							)
						)
					)
					(number "5"
						(effects
							(font
								(size 1.27 1.27)
							)
						)
					)
				)
			)
		)
	(symbol "antmicroOscillators:Oscillator_25MHz_511ABA25M0000BAGR"
			(exclude_from_sim no)
			(in_bom yes)
			(on_board yes)
			(property "Reference" "Y"
				(at 28.575 -1.905 0)
				(effects
					(font
						(size 1.27 1.27)
						(thickness 0.15)
					)
					(justify left bottom)
				)
			)
			(property "Value" "Oscillator_25MHz_511ABA25M0000BAGR"
				(at 28.575 -12.065 0)
				(effects
					(font
						(size 1.27 1.27)
						(thickness 0.15)
					)
					(justify left bottom)
					(hide yes)
				)
			)
			(property "Footprint" "antmicro-footprints:Oscillator_SMD_Skyworks_SI511_5x3.2x1.17mm"
				(at 28.575 -14.605 0)
				(effects
					(font
						(size 1.27 1.27)
						(thickness 0.15)
					)
					(justify left bottom)
					(hide yes)
				)
			)
			(property "Datasheet" "https://www.mouser.com/datasheet/2/472/si510_11-2507765.pdf"
				(at 28.575 -17.145 0)
				(effects
					(font
						(size 1.27 1.27)
						(thickness 0.15)
					)
					(justify left bottom)
					(hide yes)
				)
			)
			(property "Description" "25 MHz XO (Standard) LVPECL Oscillator 3.3V Enable/Disable 6-SMD, No Lead"
				(at 28.575 -24.765 0)
				(effects
					(font
						(size 1.27 1.27)
					)
					(justify left bottom)
					(hide yes)
				)
			)
			(property "Manufacturer" "Skyworks Solutions"
				(at 28.575 -4.445 0)
				(effects
					(font
						(size 1.27 1.27)
						(thickness 0.15)
					)
					(justify left bottom)
					(hide yes)
				)
			)
			(property "MPN" "511ABA25M0000BAGR"
				(at 28.575 -6.985 0)
				(effects
					(font
						(size 1.27 1.27)
						(thickness 0.15)
					)
					(justify left bottom)
				)
			)
			(property "Val" "25 MHz"
				(at 28.575 -9.525 0)
				(effects
					(font
						(size 1.27 1.27)
						(thickness 0.15)
					)
					(justify left bottom)
				)
			)
			(property "Author" "Antmicro"
				(at 28.575 -19.685 0)
				(effects
					(font
						(size 1.27 1.27)
						(thickness 0.15)
					)
					(justify left bottom)
					(hide yes)
				)
			)
			(property "License" "Apache-2.0"
				(at 28.575 -22.225 0)
				(effects
					(font
						(size 1.27 1.27)
						(thickness 0.15)
					)
					(justify left bottom)
					(hide yes)
				)
			)
			(property "ki_keywords" "OSCILLATOR, SMT"
				(at 0 0 0)
				(effects
					(font
						(size 1.27 1.27)
					)
					(hide yes)
				)
			)
			(symbol "Oscillator_25MHz_511ABA25M0000BAGR_1_1"
				(rectangle
					(start 2.54 2.54)
					(end 16.51 -7.62)
					(stroke
						(width 0.254)
						(type default)
					)
					(fill
						(type background)
					)
				)
				(polyline
					(pts
						(xy 7.62 -1.27) (xy 8.255 -1.27) (xy 8.255 0) (xy 8.89 0) (xy 8.89 -1.27) (xy 9.525 -1.27) (xy 9.525 0)
						(xy 10.16 0) (xy 10.16 -1.27)
					)
					(stroke
						(width 0.254)
						(type default)
					)
					(fill
						(type background)
					)
				)
				(pin power_in line
					(at 0 0 0)
					(length 2.54)
					(name "VCC"
						(effects
							(font
								(size 1.27 1.27)
							)
						)
					)
					(number "6"
						(effects
							(font
								(size 1.27 1.27)
							)
						)
					)
				)
				(pin input line
					(at 0 -2.54 0)
					(length 2.54)
					(name "EN"
						(effects
							(font
								(size 1.27 1.27)
							)
						)
					)
					(number "1"
						(effects
							(font
								(size 1.27 1.27)
							)
						)
					)
				)
				(pin power_in line
					(at 0 -5.08 0)
					(length 2.54)
					(name "GND"
						(effects
							(font
								(size 1.27 1.27)
							)
						)
					)
					(number "3"
						(effects
							(font
								(size 1.27 1.27)
							)
						)
					)
				)
				(pin no_connect line
					(at 16.51 -5.08 180)
					(length 2.54)
					(hide yes)
					(name "NC"
						(effects
							(font
								(size 1.27 1.27)
							)
						)
					)
					(number "2"
						(effects
							(font
								(size 1.27 1.27)
							)
						)
					)
				)
				(pin output line
					(at 19.05 0 180)
					(length 2.54)
					(name "OUT+"
						(effects
							(font
								(size 1.27 1.27)
							)
						)
					)
					(number "4"
						(effects
							(font
								(size 1.27 1.27)
							)
						)
					)
				)
				(pin output line
					(at 19.05 -2.54 180)
					(length 2.54)
					(name "OUT-"
						(effects
							(font
								(size 1.27 1.27)
							)
						)
					)
					(number "5"
						(effects
							(font
								(size 1.27 1.27)
							)
						)
					)
				)
			)
		)
	(symbol "antmicroPMICORControllersIdealDiodes:LTC4412IS6"
			(exclude_from_sim no)
			(in_bom yes)
			(on_board yes)
			(property "Reference" "U"
				(at 31.75 -2.54 0)
				(effects
					(font
						(size 1.27 1.27)
						(thickness 0.15)
					)
					(justify left bottom)
				)
			)
			(property "Value" "LTC4412IS6"
				(at 31.75 -5.08 0)
				(effects
					(font
						(size 1.27 1.27)
						(thickness 0.15)
					)
					(justify left bottom)
					(hide yes)
				)
			)
			(property "Footprint" "antmicro-footprints:SOT-23-6"
				(at 31.75 -7.62 0)
				(effects
					(font
						(size 1.27 1.27)
						(thickness 0.15)
					)
					(justify left bottom)
					(hide yes)
				)
			)
			(property "Datasheet" "https://www.analog.com/media/en/technical-documentation/data-sheets/4412fb.pdf"
				(at 31.75 -10.16 0)
				(effects
					(font
						(size 1.27 1.27)
						(thickness 0.15)
					)
					(justify left bottom)
					(hide yes)
				)
			)
			(property "Description" "Ideal diode controller"
				(at 31.75 -22.86 0)
				(effects
					(font
						(size 1.27 1.27)
					)
					(justify left bottom)
					(hide yes)
				)
			)
			(property "MPN" "LTC4412IS6#TRMPBF"
				(at 31.75 -12.7 0)
				(effects
					(font
						(size 1.27 1.27)
						(thickness 0.15)
					)
					(justify left bottom)
				)
			)
			(property "Manufacturer" "Analog Devices"
				(at 31.75 -15.24 0)
				(effects
					(font
						(size 1.27 1.27)
						(thickness 0.15)
					)
					(justify left bottom)
					(hide yes)
				)
			)
			(property "Author" "Antmicro"
				(at 31.75 -17.78 0)
				(effects
					(font
						(size 1.27 1.27)
						(thickness 0.15)
					)
					(justify left bottom)
					(hide yes)
				)
			)
			(property "License" "Apache-2.0"
				(at 31.75 -20.32 0)
				(effects
					(font
						(size 1.27 1.27)
						(thickness 0.15)
					)
					(justify left bottom)
					(hide yes)
				)
			)
			(property "ki_keywords" "SMT, CONTROLLER, IC, DIODE"
				(at 0 0 0)
				(effects
					(font
						(size 1.27 1.27)
					)
					(hide yes)
				)
			)
			(symbol "LTC4412IS6_1_1"
				(rectangle
					(start 2.54 2.54)
					(end 15.24 -7.62)
					(stroke
						(width 0.254)
						(type default)
					)
					(fill
						(type background)
					)
				)
				(pin power_in line
					(at 0 0 0)
					(length 2.54)
					(name "IN"
						(effects
							(font
								(size 1.27 1.27)
							)
						)
					)
					(number "1"
						(effects
							(font
								(size 1.27 1.27)
							)
						)
					)
				)
				(pin input line
					(at 0 -2.54 0)
					(length 2.54)
					(name "CTL"
						(effects
							(font
								(size 1.27 1.27)
							)
						)
					)
					(number "3"
						(effects
							(font
								(size 1.27 1.27)
							)
						)
					)
				)
				(pin power_in line
					(at 0 -5.08 0)
					(length 2.54)
					(name "GND"
						(effects
							(font
								(size 1.27 1.27)
							)
						)
					)
					(number "2"
						(effects
							(font
								(size 1.27 1.27)
							)
						)
					)
				)
				(pin input line
					(at 17.78 0 180)
					(length 2.54)
					(name "SENSE"
						(effects
							(font
								(size 1.27 1.27)
							)
						)
					)
					(number "6"
						(effects
							(font
								(size 1.27 1.27)
							)
						)
					)
				)
				(pin output line
					(at 17.78 -2.54 180)
					(length 2.54)
					(name "GATE"
						(effects
							(font
								(size 1.27 1.27)
							)
						)
					)
					(number "5"
						(effects
							(font
								(size 1.27 1.27)
							)
						)
					)
				)
				(pin output line
					(at 17.78 -5.08 180)
					(length 2.54)
					(name "STAT"
						(effects
							(font
								(size 1.27 1.27)
							)
						)
					)
					(number "4"
						(effects
							(font
								(size 1.27 1.27)
							)
						)
					)
				)
			)
		)
	(symbol "antmicroPMICVoltageRegulatorsLinear:LP2985IM5X-5.0_SOT"
			(exclude_from_sim no)
			(in_bom yes)
			(on_board yes)
			(property "Reference" "U"
				(at 33.02 -2.54 0)
				(effects
					(font
						(size 1.27 1.27)
						(thickness 0.15)
					)
					(justify left bottom)
				)
			)
			(property "Value" "LP2985IM5X-5.0_SOT"
				(at 33.02 -7.62 0)
				(effects
					(font
						(size 1.27 1.27)
						(thickness 0.15)
					)
					(justify left bottom)
					(hide yes)
				)
			)
			(property "Footprint" "antmicro-footprints:SOT-23-5"
				(at 33.02 -10.16 0)
				(effects
					(font
						(size 1.27 1.27)
						(thickness 0.15)
					)
					(justify left bottom)
					(hide yes)
				)
			)
			(property "Datasheet" "https://www.ti.com/lit/ds/symlink/lp2985-n.pdf?ts=1705246249323&ref_url=https%253A%252F%252Fwww.mouser.se%252F"
				(at 33.02 -12.7 0)
				(effects
					(font
						(size 1.27 1.27)
						(thickness 0.15)
					)
					(justify left bottom)
					(hide yes)
				)
			)
			(property "Description" "LDO voltage regulator 150-mA, 16-V, low-dropout voltage regulator with enable 5-SOT-23"
				(at 33.02 -22.86 0)
				(effects
					(font
						(size 1.27 1.27)
					)
					(justify left bottom)
					(hide yes)
				)
			)
			(property "MPN" "LP2985IM5X-5.0/NOPB"
				(at 33.02 -5.08 0)
				(effects
					(font
						(size 1.27 1.27)
						(thickness 0.15)
					)
					(justify left bottom)
				)
			)
			(property "Manufacturer" "Texas Instruments"
				(at 33.02 -15.24 0)
				(effects
					(font
						(size 1.27 1.27)
						(thickness 0.15)
					)
					(justify left bottom)
					(hide yes)
				)
			)
			(property "Author" "Antmicro"
				(at 33.02 -17.78 0)
				(effects
					(font
						(size 1.27 1.27)
						(thickness 0.15)
					)
					(justify left bottom)
					(hide yes)
				)
			)
			(property "License" "Apache-2.0"
				(at 33.02 -20.32 0)
				(effects
					(font
						(size 1.27 1.27)
						(thickness 0.15)
					)
					(justify left bottom)
					(hide yes)
				)
			)
			(property "ki_keywords" "IC, SMT, REGULATOR, LINEAR"
				(at 0 0 0)
				(effects
					(font
						(size 1.27 1.27)
					)
					(hide yes)
				)
			)
			(symbol "LP2985IM5X-5.0_SOT_1_1"
				(rectangle
					(start 2.54 2.54)
					(end 11.43 -7.62)
					(stroke
						(width 0.254)
						(type default)
					)
					(fill
						(type background)
					)
				)
				(pin power_in line
					(at 0 0 0)
					(length 2.54)
					(name "IN"
						(effects
							(font
								(size 1.27 1.27)
							)
						)
					)
					(number "1"
						(effects
							(font
								(size 1.27 1.27)
							)
						)
					)
				)
				(pin input line
					(at 0 -5.08 0)
					(length 2.54)
					(name "EN"
						(effects
							(font
								(size 1.27 1.27)
							)
						)
					)
					(number "3"
						(effects
							(font
								(size 1.27 1.27)
							)
						)
					)
				)
				(pin power_out line
					(at 13.97 0 180)
					(length 2.54)
					(name "OUT"
						(effects
							(font
								(size 1.27 1.27)
							)
						)
					)
					(number "5"
						(effects
							(font
								(size 1.27 1.27)
							)
						)
					)
				)
				(pin passive line
					(at 13.97 -2.54 180)
					(length 2.54)
					(name "BYPASS"
						(effects
							(font
								(size 1.27 1.27)
							)
						)
					)
					(number "4"
						(effects
							(font
								(size 1.27 1.27)
							)
						)
					)
				)
				(pin power_in line
					(at 13.97 -5.08 180)
					(length 2.54)
					(name "GND"
						(effects
							(font
								(size 1.27 1.27)
							)
						)
					)
					(number "2"
						(effects
							(font
								(size 1.27 1.27)
							)
						)
					)
				)
			)
		)
	(symbol "antmicroPciConnectors:OCuLink_x4_Amphenol_G14A421211112HR_CUSTOM_device_side"
			(exclude_from_sim no)
			(in_bom yes)
			(on_board yes)
			(property "Reference" "J"
				(at 39.37 -5.08 0)
				(effects
					(font
						(size 1.27 1.27)
						(thickness 0.15)
					)
					(justify left bottom)
				)
			)
			(property "Value" "OCuLink_x4_Amphenol_G14A421211112HR_CUSTOM_device_side"
				(at 39.37 -12.7 0)
				(effects
					(font
						(size 1.27 1.27)
						(thickness 0.15)
					)
					(justify left bottom)
					(hide yes)
				)
			)
			(property "Footprint" "antmicro-footprints:Amphenol_G14A421211112HR"
				(at 39.37 -15.24 0)
				(effects
					(font
						(size 1.27 1.27)
						(thickness 0.15)
					)
					(justify left bottom)
					(hide yes)
				)
			)
			(property "Datasheet" "https://cdn.amphenol-cs.com/media/wysiwyg/files/drawing/g14a421x1bxxxhr.pdf"
				(at 39.37 -17.78 0)
				(effects
					(font
						(size 1.27 1.27)
						(thickness 0.15)
					)
					(justify left bottom)
					(hide yes)
				)
			)
			(property "Description" "I/O Connectors OCulink, Receptacle, 0.5mm pitch, 4X, R/A SMT with shell leg SMT type, 30U\" gold plating, LCP, black, T&R packing"
				(at 39.37 -25.4 0)
				(effects
					(font
						(size 1.27 1.27)
					)
					(justify left bottom)
					(hide yes)
				)
			)
			(property "Manufacturer" "Amphenol"
				(at 39.37 -10.16 0)
				(effects
					(font
						(size 1.27 1.27)
						(thickness 0.15)
					)
					(justify left bottom)
					(hide yes)
				)
			)
			(property "MPN" "G14A421211112HR"
				(at 39.37 -7.62 0)
				(effects
					(font
						(size 1.27 1.27)
						(thickness 0.15)
					)
					(justify left bottom)
				)
			)
			(property "Author" "Antmicro"
				(at 39.37 -20.32 0)
				(effects
					(font
						(size 1.27 1.27)
						(thickness 0.15)
					)
					(justify left bottom)
					(hide yes)
				)
			)
			(property "License" "Apache-2.0"
				(at 39.37 -22.86 0)
				(effects
					(font
						(size 1.27 1.27)
						(thickness 0.15)
					)
					(justify left bottom)
					(hide yes)
				)
			)
			(property "ki_keywords" "SMT, CONNECTOR, PCIE"
				(at 0 0 0)
				(effects
					(font
						(size 1.27 1.27)
					)
					(hide yes)
				)
			)
			(symbol "OCuLink_x4_Amphenol_G14A421211112HR_CUSTOM_device_side_1_1"
				(rectangle
					(start 3.81 2.54)
					(end 21.59 -93.98)
					(stroke
						(width 0.254)
						(type default)
					)
					(fill
						(type background)
					)
				)
				(pin passive line
					(at 0 0 0)
					(length 3.81)
					(name "5V"
						(effects
							(font
								(size 1.27 1.27)
							)
						)
					)
					(number "A21"
						(effects
							(font
								(size 1.27 1.27)
							)
						)
					)
				)
				(pin passive line
					(at 0 0 0)
					(length 3.81)
					(hide yes)
					(name "5V"
						(effects
							(font
								(size 1.27 1.27)
							)
						)
					)
					(number "B1"
						(effects
							(font
								(size 1.27 1.27)
							)
						)
					)
				)
				(pin power_in line
					(at 0 -2.54 0)
					(length 3.81)
					(name "V_{ACT}_RX_3V3"
						(effects
							(font
								(size 1.27 1.27)
							)
						)
					)
					(number "A1"
						(effects
							(font
								(size 1.27 1.27)
							)
						)
					)
				)
				(pin power_in line
					(at 0 -5.08 0)
					(length 3.81)
					(name "V_{ACT}_TX_3V3"
						(effects
							(font
								(size 1.27 1.27)
							)
						)
					)
					(number "B21"
						(effects
							(font
								(size 1.27 1.27)
							)
						)
					)
				)
				(pin bidirectional line
					(at 0 -10.16 0)
					(length 3.81)
					(name "SCL"
						(effects
							(font
								(size 1.27 1.27)
							)
						)
					)
					(number "A9"
						(effects
							(font
								(size 1.27 1.27)
							)
						)
					)
				)
				(pin bidirectional line
					(at 0 -12.7 0)
					(length 3.81)
					(name "SDA"
						(effects
							(font
								(size 1.27 1.27)
							)
						)
					)
					(number "A10"
						(effects
							(font
								(size 1.27 1.27)
							)
						)
					)
				)
				(pin bidirectional line
					(at 0 -17.78 0)
					(length 3.81)
					(name "VSP1"
						(effects
							(font
								(size 1.27 1.27)
							)
						)
					)
					(number "B12"
						(effects
							(font
								(size 1.27 1.27)
							)
						)
					)
				)
				(pin bidirectional line
					(at 0 -20.32 0)
					(length 3.81)
					(name "VSP2"
						(effects
							(font
								(size 1.27 1.27)
							)
						)
					)
					(number "B13"
						(effects
							(font
								(size 1.27 1.27)
							)
						)
					)
				)
				(pin bidirectional line
					(at 0 -25.4 0)
					(length 3.81)
					(name "~{PERST}"
						(effects
							(font
								(size 1.27 1.27)
							)
						)
					)
					(number "A12"
						(effects
							(font
								(size 1.27 1.27)
							)
						)
					)
				)
				(pin bidirectional line
					(at 0 -27.94 0)
					(length 3.81)
					(name "~{CPRSNT}"
						(effects
							(font
								(size 1.27 1.27)
							)
						)
					)
					(number "A13"
						(effects
							(font
								(size 1.27 1.27)
							)
						)
					)
				)
				(pin bidirectional line
					(at 0 -30.48 0)
					(length 3.81)
					(name "~{CWAKE}"
						(effects
							(font
								(size 1.27 1.27)
							)
						)
					)
					(number "B10"
						(effects
							(font
								(size 1.27 1.27)
							)
						)
					)
				)
				(pin input line
					(at 0 -35.56 0)
					(length 3.81)
					(name "PET0+"
						(effects
							(font
								(size 1.27 1.27)
							)
						)
					)
					(number "B3"
						(effects
							(font
								(size 1.27 1.27)
							)
						)
					)
				)
				(pin input line
					(at 0 -38.1 0)
					(length 3.81)
					(name "PET0-"
						(effects
							(font
								(size 1.27 1.27)
							)
						)
					)
					(number "B4"
						(effects
							(font
								(size 1.27 1.27)
							)
						)
					)
				)
				(pin input line
					(at 0 -43.18 0)
					(length 3.81)
					(name "PET1+"
						(effects
							(font
								(size 1.27 1.27)
							)
						)
					)
					(number "B6"
						(effects
							(font
								(size 1.27 1.27)
							)
						)
					)
				)
				(pin input line
					(at 0 -45.72 0)
					(length 3.81)
					(name "PET1-"
						(effects
							(font
								(size 1.27 1.27)
							)
						)
					)
					(number "B7"
						(effects
							(font
								(size 1.27 1.27)
							)
						)
					)
				)
				(pin input line
					(at 0 -50.8 0)
					(length 3.81)
					(name "PET2+"
						(effects
							(font
								(size 1.27 1.27)
							)
						)
					)
					(number "B15"
						(effects
							(font
								(size 1.27 1.27)
							)
						)
					)
				)
				(pin input line
					(at 0 -53.34 0)
					(length 3.81)
					(name "PET2-"
						(effects
							(font
								(size 1.27 1.27)
							)
						)
					)
					(number "B16"
						(effects
							(font
								(size 1.27 1.27)
							)
						)
					)
				)
				(pin input line
					(at 0 -58.42 0)
					(length 3.81)
					(name "PET3+"
						(effects
							(font
								(size 1.27 1.27)
							)
						)
					)
					(number "B18"
						(effects
							(font
								(size 1.27 1.27)
							)
						)
					)
				)
				(pin input line
					(at 0 -60.96 0)
					(length 3.81)
					(name "PET3-"
						(effects
							(font
								(size 1.27 1.27)
							)
						)
					)
					(number "B19"
						(effects
							(font
								(size 1.27 1.27)
							)
						)
					)
				)
				(pin output line
					(at 0 -66.04 0)
					(length 3.81)
					(name "PER0+"
						(effects
							(font
								(size 1.27 1.27)
							)
						)
					)
					(number "A3"
						(effects
							(font
								(size 1.27 1.27)
							)
						)
					)
				)
				(pin output line
					(at 0 -68.58 0)
					(length 3.81)
					(name "PER0-"
						(effects
							(font
								(size 1.27 1.27)
							)
						)
					)
					(number "A4"
						(effects
							(font
								(size 1.27 1.27)
							)
						)
					)
				)
				(pin output line
					(at 0 -73.66 0)
					(length 3.81)
					(name "PER1+"
						(effects
							(font
								(size 1.27 1.27)
							)
						)
					)
					(number "A6"
						(effects
							(font
								(size 1.27 1.27)
							)
						)
					)
				)
				(pin output line
					(at 0 -76.2 0)
					(length 3.81)
					(name "PER1-"
						(effects
							(font
								(size 1.27 1.27)
							)
						)
					)
					(number "A7"
						(effects
							(font
								(size 1.27 1.27)
							)
						)
					)
				)
				(pin output line
					(at 0 -81.28 0)
					(length 3.81)
					(name "PER2+"
						(effects
							(font
								(size 1.27 1.27)
							)
						)
					)
					(number "A15"
						(effects
							(font
								(size 1.27 1.27)
							)
						)
					)
				)
				(pin output line
					(at 0 -83.82 0)
					(length 3.81)
					(name "PER2-"
						(effects
							(font
								(size 1.27 1.27)
							)
						)
					)
					(number "A16"
						(effects
							(font
								(size 1.27 1.27)
							)
						)
					)
				)
				(pin output line
					(at 0 -88.9 0)
					(length 3.81)
					(name "PER3+"
						(effects
							(font
								(size 1.27 1.27)
							)
						)
					)
					(number "A18"
						(effects
							(font
								(size 1.27 1.27)
							)
						)
					)
				)
				(pin output line
					(at 0 -91.44 0)
					(length 3.81)
					(name "PER3-"
						(effects
							(font
								(size 1.27 1.27)
							)
						)
					)
					(number "A19"
						(effects
							(font
								(size 1.27 1.27)
							)
						)
					)
				)
				(pin no_connect line
					(at 21.59 -76.2 180)
					(length 3.81)
					(hide yes)
					(name "NC"
						(effects
							(font
								(size 1.27 1.27)
							)
						)
					)
					(number "B9"
						(effects
							(font
								(size 1.27 1.27)
							)
						)
					)
				)
				(pin passive line
					(at 25.4 -88.9 180)
					(length 3.81)
					(name "SH"
						(effects
							(font
								(size 1.27 1.27)
							)
						)
					)
					(number "SH"
						(effects
							(font
								(size 1.27 1.27)
							)
						)
					)
				)
				(pin passive line
					(at 25.4 -91.44 180)
					(length 3.81)
					(name "GND"
						(effects
							(font
								(size 1.27 1.27)
							)
						)
					)
					(number "A11"
						(effects
							(font
								(size 1.27 1.27)
							)
						)
					)
				)
				(pin passive line
					(at 25.4 -91.44 180)
					(length 3.81)
					(hide yes)
					(name "GND"
						(effects
							(font
								(size 1.27 1.27)
							)
						)
					)
					(number "A14"
						(effects
							(font
								(size 1.27 1.27)
							)
						)
					)
				)
				(pin passive line
					(at 25.4 -91.44 180)
					(length 3.81)
					(hide yes)
					(name "GND"
						(effects
							(font
								(size 1.27 1.27)
							)
						)
					)
					(number "A17"
						(effects
							(font
								(size 1.27 1.27)
							)
						)
					)
				)
				(pin passive line
					(at 25.4 -91.44 180)
					(length 3.81)
					(hide yes)
					(name "GND"
						(effects
							(font
								(size 1.27 1.27)
							)
						)
					)
					(number "A2"
						(effects
							(font
								(size 1.27 1.27)
							)
						)
					)
				)
				(pin passive line
					(at 25.4 -91.44 180)
					(length 3.81)
					(hide yes)
					(name "GND"
						(effects
							(font
								(size 1.27 1.27)
							)
						)
					)
					(number "A20"
						(effects
							(font
								(size 1.27 1.27)
							)
						)
					)
				)
				(pin passive line
					(at 25.4 -91.44 180)
					(length 3.81)
					(hide yes)
					(name "GND"
						(effects
							(font
								(size 1.27 1.27)
							)
						)
					)
					(number "A5"
						(effects
							(font
								(size 1.27 1.27)
							)
						)
					)
				)
				(pin passive line
					(at 25.4 -91.44 180)
					(length 3.81)
					(hide yes)
					(name "GND"
						(effects
							(font
								(size 1.27 1.27)
							)
						)
					)
					(number "A8"
						(effects
							(font
								(size 1.27 1.27)
							)
						)
					)
				)
				(pin passive line
					(at 25.4 -91.44 180)
					(length 3.81)
					(hide yes)
					(name "GND"
						(effects
							(font
								(size 1.27 1.27)
							)
						)
					)
					(number "B11"
						(effects
							(font
								(size 1.27 1.27)
							)
						)
					)
				)
				(pin passive line
					(at 25.4 -91.44 180)
					(length 3.81)
					(hide yes)
					(name "GND"
						(effects
							(font
								(size 1.27 1.27)
							)
						)
					)
					(number "B14"
						(effects
							(font
								(size 1.27 1.27)
							)
						)
					)
				)
				(pin passive line
					(at 25.4 -91.44 180)
					(length 3.81)
					(hide yes)
					(name "GND"
						(effects
							(font
								(size 1.27 1.27)
							)
						)
					)
					(number "B17"
						(effects
							(font
								(size 1.27 1.27)
							)
						)
					)
				)
				(pin passive line
					(at 25.4 -91.44 180)
					(length 3.81)
					(hide yes)
					(name "GND"
						(effects
							(font
								(size 1.27 1.27)
							)
						)
					)
					(number "B2"
						(effects
							(font
								(size 1.27 1.27)
							)
						)
					)
				)
				(pin passive line
					(at 25.4 -91.44 180)
					(length 3.81)
					(hide yes)
					(name "GND"
						(effects
							(font
								(size 1.27 1.27)
							)
						)
					)
					(number "B20"
						(effects
							(font
								(size 1.27 1.27)
							)
						)
					)
				)
				(pin passive line
					(at 25.4 -91.44 180)
					(length 3.81)
					(hide yes)
					(name "GND"
						(effects
							(font
								(size 1.27 1.27)
							)
						)
					)
					(number "B5"
						(effects
							(font
								(size 1.27 1.27)
							)
						)
					)
				)
				(pin passive line
					(at 25.4 -91.44 180)
					(length 3.81)
					(hide yes)
					(name "GND"
						(effects
							(font
								(size 1.27 1.27)
							)
						)
					)
					(number "B8"
						(effects
							(font
								(size 1.27 1.27)
							)
						)
					)
				)
			)
		)
	(symbol "antmicroResistors0402:R_0R_0402"
			(pin_numbers
				(hide yes)
			)
			(pin_names
				(hide yes)
			)
			(exclude_from_sim no)
			(in_bom yes)
			(on_board yes)
			(property "Reference" "R"
				(at 20.32 -5.08 0)
				(effects
					(font
						(size 1.27 1.27)
						(thickness 0.15)
					)
					(justify left bottom)
				)
			)
			(property "Value" "R_0R_0402"
				(at 20.32 -12.7 0)
				(effects
					(font
						(size 1.27 1.27)
						(thickness 0.15)
					)
					(justify left bottom)
					(hide yes)
				)
			)
			(property "Footprint" "antmicro-footprints:R_0402_1005Metric"
				(at 20.32 -15.24 0)
				(effects
					(font
						(size 1.27 1.27)
						(thickness 0.15)
					)
					(justify left bottom)
					(hide yes)
				)
			)
			(property "Datasheet" "https://industrial.panasonic.com/cdbs/www-data/pdf/RDA0000/AOA0000C301.pdf"
				(at 20.32 -17.78 0)
				(effects
					(font
						(size 1.27 1.27)
						(thickness 0.15)
					)
					(justify left bottom)
					(hide yes)
				)
			)
			(property "Description" "SMD Chip Resistor, Jumper, 0 ohm, 100 mW, 0402 [1005 Metric], Thick Film, General Purpose"
				(at 20.32 -33.02 0)
				(effects
					(font
						(size 1.27 1.27)
					)
					(justify left bottom)
					(hide yes)
				)
			)
			(property "MPN" "ERJ2GE0R00X"
				(at 20.32 -20.32 0)
				(effects
					(font
						(size 1.27 1.27)
						(thickness 0.15)
					)
					(justify left bottom)
					(hide yes)
				)
			)
			(property "Manufacturer" "Panasonic"
				(at 20.32 -22.86 0)
				(effects
					(font
						(size 1.27 1.27)
						(thickness 0.15)
					)
					(justify left bottom)
					(hide yes)
				)
			)
			(property "License" "Apache-2.0"
				(at 20.32 -25.4 0)
				(effects
					(font
						(size 1.27 1.27)
						(thickness 0.15)
					)
					(justify left bottom)
					(hide yes)
				)
			)
			(property "Author" "Antmicro"
				(at 20.32 -27.94 0)
				(effects
					(font
						(size 1.27 1.27)
						(thickness 0.15)
					)
					(justify left bottom)
					(hide yes)
				)
			)
			(property "Val" "0R"
				(at 20.32 -7.62 0)
				(effects
					(font
						(size 1.27 1.27)
						(thickness 0.15)
					)
					(justify left bottom)
				)
			)
			(property "Tolerance" "~"
				(at 20.32 -10.16 0)
				(effects
					(font
						(size 1.27 1.27)
					)
					(justify left bottom)
					(hide yes)
				)
			)
			(property "Current" "1A"
				(at 20.32 -30.48 0)
				(effects
					(font
						(size 1.27 1.27)
						(thickness 0.15)
					)
					(justify left bottom)
					(hide yes)
				)
			)
			(property "ki_keywords" "0402, SMT, RESISTOR, PASSIVE"
				(at 0 0 0)
				(effects
					(font
						(size 1.27 1.27)
					)
					(hide yes)
				)
			)
			(symbol "R_0R_0402_0_1"
				(rectangle
					(start 0.635 0.889)
					(end 4.445 -0.889)
					(stroke
						(width 0.254)
						(type default)
					)
					(fill
						(type none)
					)
				)
			)
			(symbol "R_0R_0402_1_1"
				(pin passive line
					(at 0 0 0)
					(length 0.635)
					(name "~"
						(effects
							(font
								(size 1.27 1.27)
							)
						)
					)
					(number "1"
						(effects
							(font
								(size 1.27 1.27)
							)
						)
					)
				)
				(pin passive line
					(at 5.08 0 180)
					(length 0.635)
					(name "~"
						(effects
							(font
								(size 1.27 1.27)
							)
						)
					)
					(number "2"
						(effects
							(font
								(size 1.27 1.27)
							)
						)
					)
				)
			)
		)
	(symbol "antmicroResistors0402:R_100R_0402"
			(pin_numbers
				(hide yes)
			)
			(pin_names
				(hide yes)
			)
			(exclude_from_sim no)
			(in_bom yes)
			(on_board yes)
			(property "Reference" "R"
				(at 20.32 -5.08 0)
				(effects
					(font
						(size 1.27 1.27)
						(thickness 0.15)
					)
					(justify left bottom)
				)
			)
			(property "Value" "R_100R_0402"
				(at 20.32 -12.7 0)
				(effects
					(font
						(size 1.27 1.27)
						(thickness 0.15)
					)
					(justify left bottom)
					(hide yes)
				)
			)
			(property "Footprint" "antmicro-footprints:R_0402_1005Metric"
				(at 20.32 -15.24 0)
				(effects
					(font
						(size 1.27 1.27)
						(thickness 0.15)
					)
					(justify left bottom)
					(hide yes)
				)
			)
			(property "Datasheet" "https://www.bourns.com/docs/product-datasheets/cr.pdf"
				(at 20.32 -17.78 0)
				(effects
					(font
						(size 1.27 1.27)
						(thickness 0.15)
					)
					(justify left bottom)
					(hide yes)
				)
			)
			(property "Description" "SMD Chip Resistor, 100 ohm, ± 1%, 62.5 mW, 0402 [1005 Metric], Thick Film, General Purpose"
				(at 20.32 -30.48 0)
				(effects
					(font
						(size 1.27 1.27)
					)
					(justify left bottom)
					(hide yes)
				)
			)
			(property "MPN" "CR0402-FX-1000GLF"
				(at 20.32 -20.32 0)
				(effects
					(font
						(size 1.27 1.27)
						(thickness 0.15)
					)
					(justify left bottom)
					(hide yes)
				)
			)
			(property "Manufacturer" "Bourns"
				(at 20.32 -22.86 0)
				(effects
					(font
						(size 1.27 1.27)
						(thickness 0.15)
					)
					(justify left bottom)
					(hide yes)
				)
			)
			(property "License" "Apache-2.0"
				(at 20.32 -25.4 0)
				(effects
					(font
						(size 1.27 1.27)
						(thickness 0.15)
					)
					(justify left bottom)
					(hide yes)
				)
			)
			(property "Author" "Antmicro"
				(at 20.32 -27.94 0)
				(effects
					(font
						(size 1.27 1.27)
						(thickness 0.15)
					)
					(justify left bottom)
					(hide yes)
				)
			)
			(property "Val" "100R"
				(at 20.32 -7.62 0)
				(effects
					(font
						(size 1.27 1.27)
						(thickness 0.15)
					)
					(justify left bottom)
				)
			)
			(property "Tolerance" "1%"
				(at 20.32 -10.16 0)
				(effects
					(font
						(size 1.27 1.27)
					)
					(justify left bottom)
					(hide yes)
				)
			)
			(property "ki_keywords" "0402, SMT, RESISTOR, PASSIVE"
				(at 0 0 0)
				(effects
					(font
						(size 1.27 1.27)
					)
					(hide yes)
				)
			)
			(symbol "R_100R_0402_0_1"
				(rectangle
					(start 0.635 0.889)
					(end 4.445 -0.889)
					(stroke
						(width 0.254)
						(type default)
					)
					(fill
						(type none)
					)
				)
			)
			(symbol "R_100R_0402_1_1"
				(pin passive line
					(at 0 0 0)
					(length 0.635)
					(name "~"
						(effects
							(font
								(size 1.27 1.27)
							)
						)
					)
					(number "1"
						(effects
							(font
								(size 1.27 1.27)
							)
						)
					)
				)
				(pin passive line
					(at 5.08 0 180)
					(length 0.635)
					(name "~"
						(effects
							(font
								(size 1.27 1.27)
							)
						)
					)
					(number "2"
						(effects
							(font
								(size 1.27 1.27)
							)
						)
					)
				)
			)
		)
	(symbol "antmicroResistors0402:R_100k_0402"
			(pin_numbers
				(hide yes)
			)
			(pin_names
				(hide yes)
			)
			(exclude_from_sim no)
			(in_bom yes)
			(on_board yes)
			(property "Reference" "R"
				(at 20.32 -5.08 0)
				(effects
					(font
						(size 1.27 1.27)
						(thickness 0.15)
					)
					(justify left bottom)
				)
			)
			(property "Value" "R_100k_0402"
				(at 20.32 -12.7 0)
				(effects
					(font
						(size 1.27 1.27)
						(thickness 0.15)
					)
					(justify left bottom)
					(hide yes)
				)
			)
			(property "Footprint" "antmicro-footprints:R_0402_1005Metric"
				(at 20.32 -15.24 0)
				(effects
					(font
						(size 1.27 1.27)
						(thickness 0.15)
					)
					(justify left bottom)
					(hide yes)
				)
			)
			(property "Datasheet" "https://www.bourns.com/docs/product-datasheets/cr.pdf"
				(at 20.32 -17.78 0)
				(effects
					(font
						(size 1.27 1.27)
						(thickness 0.15)
					)
					(justify left bottom)
					(hide yes)
				)
			)
			(property "Description" "SMD Chip Resistor, 100 kohm, ± 1%, 62.5 mW, 0402 [1005 Metric], Thick Film, General Purpose"
				(at 20.32 -30.48 0)
				(effects
					(font
						(size 1.27 1.27)
					)
					(justify left bottom)
					(hide yes)
				)
			)
			(property "MPN" "CR0402-FX-1003GLF"
				(at 20.32 -20.32 0)
				(effects
					(font
						(size 1.27 1.27)
						(thickness 0.15)
					)
					(justify left bottom)
					(hide yes)
				)
			)
			(property "Manufacturer" "Bourns"
				(at 20.32 -22.86 0)
				(effects
					(font
						(size 1.27 1.27)
						(thickness 0.15)
					)
					(justify left bottom)
					(hide yes)
				)
			)
			(property "License" "Apache-2.0"
				(at 20.32 -25.4 0)
				(effects
					(font
						(size 1.27 1.27)
						(thickness 0.15)
					)
					(justify left bottom)
					(hide yes)
				)
			)
			(property "Author" "Antmicro"
				(at 20.32 -27.94 0)
				(effects
					(font
						(size 1.27 1.27)
						(thickness 0.15)
					)
					(justify left bottom)
					(hide yes)
				)
			)
			(property "Val" "100k"
				(at 20.32 -7.62 0)
				(effects
					(font
						(size 1.27 1.27)
						(thickness 0.15)
					)
					(justify left bottom)
				)
			)
			(property "Tolerance" "1%"
				(at 20.32 -10.16 0)
				(effects
					(font
						(size 1.27 1.27)
					)
					(justify left bottom)
					(hide yes)
				)
			)
			(property "ki_keywords" "0402, SMT, RESISTOR, PASSIVE"
				(at 0 0 0)
				(effects
					(font
						(size 1.27 1.27)
					)
					(hide yes)
				)
			)
			(symbol "R_100k_0402_0_1"
				(rectangle
					(start 0.635 0.889)
					(end 4.445 -0.889)
					(stroke
						(width 0.254)
						(type default)
					)
					(fill
						(type none)
					)
				)
			)
			(symbol "R_100k_0402_1_1"
				(pin passive line
					(at 0 0 0)
					(length 0.635)
					(name "~"
						(effects
							(font
								(size 1.27 1.27)
							)
						)
					)
					(number "1"
						(effects
							(font
								(size 1.27 1.27)
							)
						)
					)
				)
				(pin passive line
					(at 5.08 0 180)
					(length 0.635)
					(name "~"
						(effects
							(font
								(size 1.27 1.27)
							)
						)
					)
					(number "2"
						(effects
							(font
								(size 1.27 1.27)
							)
						)
					)
				)
			)
		)
	(symbol "antmicroResistors0402:R_10R_0402"
			(pin_numbers
				(hide yes)
			)
			(pin_names
				(hide yes)
			)
			(exclude_from_sim no)
			(in_bom yes)
			(on_board yes)
			(property "Reference" "R"
				(at 20.32 -5.08 0)
				(effects
					(font
						(size 1.27 1.27)
						(thickness 0.15)
					)
					(justify left bottom)
				)
			)
			(property "Value" "R_10R_0402"
				(at 20.32 -12.7 0)
				(effects
					(font
						(size 1.27 1.27)
						(thickness 0.15)
					)
					(justify left bottom)
					(hide yes)
				)
			)
			(property "Footprint" "antmicro-footprints:R_0402_1005Metric"
				(at 20.32 -15.24 0)
				(effects
					(font
						(size 1.27 1.27)
						(thickness 0.15)
					)
					(justify left bottom)
					(hide yes)
				)
			)
			(property "Datasheet" "https://www.bourns.com/docs/product-datasheets/cr.pdf"
				(at 20.32 -17.78 0)
				(effects
					(font
						(size 1.27 1.27)
						(thickness 0.15)
					)
					(justify left bottom)
					(hide yes)
				)
			)
			(property "Description" "SMD Chip Resistor, 10 ohm, ± 1%, 62.5 mW, 0402 [1005 Metric], Thick Film, General Purpose"
				(at 20.32 -30.48 0)
				(effects
					(font
						(size 1.27 1.27)
					)
					(justify left bottom)
					(hide yes)
				)
			)
			(property "MPN" "CR0402-FX-10R0GLF"
				(at 20.32 -20.32 0)
				(effects
					(font
						(size 1.27 1.27)
						(thickness 0.15)
					)
					(justify left bottom)
					(hide yes)
				)
			)
			(property "Manufacturer" "Bourns"
				(at 20.32 -22.86 0)
				(effects
					(font
						(size 1.27 1.27)
						(thickness 0.15)
					)
					(justify left bottom)
					(hide yes)
				)
			)
			(property "License" "Apache-2.0"
				(at 20.32 -25.4 0)
				(effects
					(font
						(size 1.27 1.27)
						(thickness 0.15)
					)
					(justify left bottom)
					(hide yes)
				)
			)
			(property "Author" "Antmicro"
				(at 20.32 -27.94 0)
				(effects
					(font
						(size 1.27 1.27)
						(thickness 0.15)
					)
					(justify left bottom)
					(hide yes)
				)
			)
			(property "Val" "10R"
				(at 20.32 -7.62 0)
				(effects
					(font
						(size 1.27 1.27)
						(thickness 0.15)
					)
					(justify left bottom)
				)
			)
			(property "Tolerance" "1%"
				(at 20.32 -10.16 0)
				(effects
					(font
						(size 1.27 1.27)
					)
					(justify left bottom)
					(hide yes)
				)
			)
			(property "ki_keywords" "0402, SMT, RESISTOR, PASSIVE"
				(at 0 0 0)
				(effects
					(font
						(size 1.27 1.27)
					)
					(hide yes)
				)
			)
			(symbol "R_10R_0402_0_1"
				(rectangle
					(start 0.635 0.889)
					(end 4.445 -0.889)
					(stroke
						(width 0.254)
						(type default)
					)
					(fill
						(type none)
					)
				)
			)
			(symbol "R_10R_0402_1_1"
				(pin passive line
					(at 0 0 0)
					(length 0.635)
					(name "~"
						(effects
							(font
								(size 1.27 1.27)
							)
						)
					)
					(number "1"
						(effects
							(font
								(size 1.27 1.27)
							)
						)
					)
				)
				(pin passive line
					(at 5.08 0 180)
					(length 0.635)
					(name "~"
						(effects
							(font
								(size 1.27 1.27)
							)
						)
					)
					(number "2"
						(effects
							(font
								(size 1.27 1.27)
							)
						)
					)
				)
			)
		)
	(symbol "antmicroResistors0402:R_10k_0402"
			(pin_numbers
				(hide yes)
			)
			(pin_names
				(hide yes)
			)
			(exclude_from_sim no)
			(in_bom yes)
			(on_board yes)
			(property "Reference" "R"
				(at 20.32 -5.08 0)
				(effects
					(font
						(size 1.27 1.27)
						(thickness 0.15)
					)
					(justify left bottom)
				)
			)
			(property "Value" "R_10k_0402"
				(at 20.32 -12.7 0)
				(effects
					(font
						(size 1.27 1.27)
						(thickness 0.15)
					)
					(justify left bottom)
					(hide yes)
				)
			)
			(property "Footprint" "antmicro-footprints:R_0402_1005Metric"
				(at 20.32 -15.24 0)
				(effects
					(font
						(size 1.27 1.27)
						(thickness 0.15)
					)
					(justify left bottom)
					(hide yes)
				)
			)
			(property "Datasheet" "https://www.bourns.com/docs/product-datasheets/cr.pdf"
				(at 20.32 -17.78 0)
				(effects
					(font
						(size 1.27 1.27)
						(thickness 0.15)
					)
					(justify left bottom)
					(hide yes)
				)
			)
			(property "Description" "SMD Chip Resistor, 10 kohm, ± 1%, 62.5 mW, 0402 [1005 Metric], Thick Film, General Purpose"
				(at 20.32 -30.48 0)
				(effects
					(font
						(size 1.27 1.27)
					)
					(justify left bottom)
					(hide yes)
				)
			)
			(property "MPN" "CR0402-FX-1002GLF"
				(at 20.32 -20.32 0)
				(effects
					(font
						(size 1.27 1.27)
						(thickness 0.15)
					)
					(justify left bottom)
					(hide yes)
				)
			)
			(property "Manufacturer" "Bourns"
				(at 20.32 -22.86 0)
				(effects
					(font
						(size 1.27 1.27)
						(thickness 0.15)
					)
					(justify left bottom)
					(hide yes)
				)
			)
			(property "License" "Apache-2.0"
				(at 20.32 -25.4 0)
				(effects
					(font
						(size 1.27 1.27)
						(thickness 0.15)
					)
					(justify left bottom)
					(hide yes)
				)
			)
			(property "Author" "Antmicro"
				(at 20.32 -27.94 0)
				(effects
					(font
						(size 1.27 1.27)
						(thickness 0.15)
					)
					(justify left bottom)
					(hide yes)
				)
			)
			(property "Val" "10k"
				(at 20.32 -7.62 0)
				(effects
					(font
						(size 1.27 1.27)
						(thickness 0.15)
					)
					(justify left bottom)
				)
			)
			(property "Tolerance" "1%"
				(at 20.32 -10.16 0)
				(effects
					(font
						(size 1.27 1.27)
					)
					(justify left bottom)
					(hide yes)
				)
			)
			(property "ki_keywords" "0402, SMT, RESISTOR, PASSIVE"
				(at 0 0 0)
				(effects
					(font
						(size 1.27 1.27)
					)
					(hide yes)
				)
			)
			(symbol "R_10k_0402_0_1"
				(rectangle
					(start 0.635 0.889)
					(end 4.445 -0.889)
					(stroke
						(width 0.254)
						(type default)
					)
					(fill
						(type none)
					)
				)
			)
			(symbol "R_10k_0402_1_1"
				(pin passive line
					(at 0 0 0)
					(length 0.635)
					(name "~"
						(effects
							(font
								(size 1.27 1.27)
							)
						)
					)
					(number "1"
						(effects
							(font
								(size 1.27 1.27)
							)
						)
					)
				)
				(pin passive line
					(at 5.08 0 180)
					(length 0.635)
					(name "~"
						(effects
							(font
								(size 1.27 1.27)
							)
						)
					)
					(number "2"
						(effects
							(font
								(size 1.27 1.27)
							)
						)
					)
				)
			)
		)
	(symbol "antmicroResistors0402:R_150R_0402"
			(pin_numbers
				(hide yes)
			)
			(pin_names
				(hide yes)
			)
			(exclude_from_sim no)
			(in_bom yes)
			(on_board yes)
			(property "Reference" "R"
				(at 20.32 -5.08 0)
				(effects
					(font
						(size 1.27 1.27)
						(thickness 0.15)
					)
					(justify left bottom)
				)
			)
			(property "Value" "R_150R_0402"
				(at 20.32 -12.7 0)
				(effects
					(font
						(size 1.27 1.27)
						(thickness 0.15)
					)
					(justify left bottom)
					(hide yes)
				)
			)
			(property "Footprint" "antmicro-footprints:R_0402_1005Metric"
				(at 20.32 -15.24 0)
				(effects
					(font
						(size 1.27 1.27)
						(thickness 0.15)
					)
					(justify left bottom)
					(hide yes)
				)
			)
			(property "Datasheet" "https://www.bourns.com/docs/product-datasheets/cr.pdf"
				(at 20.32 -17.78 0)
				(effects
					(font
						(size 1.27 1.27)
						(thickness 0.15)
					)
					(justify left bottom)
					(hide yes)
				)
			)
			(property "Description" "SMD Chip Resistor, 150 ohm, ± 1%, 62.5 mW, 0402 [1005 Metric], Thick Film, General Purpose"
				(at 20.32 -30.48 0)
				(effects
					(font
						(size 1.27 1.27)
					)
					(justify left bottom)
					(hide yes)
				)
			)
			(property "MPN" "CR0402-FX-1500GLF"
				(at 20.32 -20.32 0)
				(effects
					(font
						(size 1.27 1.27)
						(thickness 0.15)
					)
					(justify left bottom)
					(hide yes)
				)
			)
			(property "Manufacturer" "Bourns"
				(at 20.32 -22.86 0)
				(effects
					(font
						(size 1.27 1.27)
						(thickness 0.15)
					)
					(justify left bottom)
					(hide yes)
				)
			)
			(property "License" "Apache-2.0"
				(at 20.32 -25.4 0)
				(effects
					(font
						(size 1.27 1.27)
						(thickness 0.15)
					)
					(justify left bottom)
					(hide yes)
				)
			)
			(property "Author" "Antmicro"
				(at 20.32 -27.94 0)
				(effects
					(font
						(size 1.27 1.27)
						(thickness 0.15)
					)
					(justify left bottom)
					(hide yes)
				)
			)
			(property "Val" "150R"
				(at 20.32 -7.62 0)
				(effects
					(font
						(size 1.27 1.27)
						(thickness 0.15)
					)
					(justify left bottom)
				)
			)
			(property "Tolerance" "1%"
				(at 20.32 -10.16 0)
				(effects
					(font
						(size 1.27 1.27)
					)
					(justify left bottom)
					(hide yes)
				)
			)
			(property "ki_keywords" "0402, SMT, RESISTOR, PASSIVE"
				(at 0 0 0)
				(effects
					(font
						(size 1.27 1.27)
					)
					(hide yes)
				)
			)
			(symbol "R_150R_0402_0_1"
				(rectangle
					(start 0.635 0.889)
					(end 4.445 -0.889)
					(stroke
						(width 0.254)
						(type default)
					)
					(fill
						(type none)
					)
				)
			)
			(symbol "R_150R_0402_1_1"
				(pin passive line
					(at 0 0 0)
					(length 0.635)
					(name "~"
						(effects
							(font
								(size 1.27 1.27)
							)
						)
					)
					(number "1"
						(effects
							(font
								(size 1.27 1.27)
							)
						)
					)
				)
				(pin passive line
					(at 5.08 0 180)
					(length 0.635)
					(name "~"
						(effects
							(font
								(size 1.27 1.27)
							)
						)
					)
					(number "2"
						(effects
							(font
								(size 1.27 1.27)
							)
						)
					)
				)
			)
		)
	(symbol "antmicroResistors0402:R_16k_0402"
			(pin_numbers
				(hide yes)
			)
			(pin_names
				(hide yes)
			)
			(exclude_from_sim no)
			(in_bom yes)
			(on_board yes)
			(property "Reference" "R"
				(at 20.32 -5.08 0)
				(effects
					(font
						(size 1.27 1.27)
						(thickness 0.15)
					)
					(justify left bottom)
				)
			)
			(property "Value" "R_16k_0402"
				(at 20.32 -12.7 0)
				(effects
					(font
						(size 1.27 1.27)
						(thickness 0.15)
					)
					(justify left bottom)
					(hide yes)
				)
			)
			(property "Footprint" "antmicro-footprints:R_0402_1005Metric"
				(at 20.32 -15.24 0)
				(effects
					(font
						(size 1.27 1.27)
						(thickness 0.15)
					)
					(justify left bottom)
					(hide yes)
				)
			)
			(property "Datasheet" "https://www.bourns.com/docs/product-datasheets/cr.pdf"
				(at 20.32 -17.78 0)
				(effects
					(font
						(size 1.27 1.27)
						(thickness 0.15)
					)
					(justify left bottom)
					(hide yes)
				)
			)
			(property "Description" "SMD Chip Resistor"
				(at 20.32 -30.48 0)
				(effects
					(font
						(size 1.27 1.27)
					)
					(justify left bottom)
					(hide yes)
				)
			)
			(property "MPN" "CR0402-FX-1602GLF"
				(at 20.32 -20.32 0)
				(effects
					(font
						(size 1.27 1.27)
						(thickness 0.15)
					)
					(justify left bottom)
					(hide yes)
				)
			)
			(property "Manufacturer" "Bourns"
				(at 20.32 -22.86 0)
				(effects
					(font
						(size 1.27 1.27)
						(thickness 0.15)
					)
					(justify left bottom)
					(hide yes)
				)
			)
			(property "License" "Apache-2.0"
				(at 20.32 -25.4 0)
				(effects
					(font
						(size 1.27 1.27)
						(thickness 0.15)
					)
					(justify left bottom)
					(hide yes)
				)
			)
			(property "Author" "Antmicro"
				(at 20.32 -27.94 0)
				(effects
					(font
						(size 1.27 1.27)
						(thickness 0.15)
					)
					(justify left bottom)
					(hide yes)
				)
			)
			(property "Val" "16k"
				(at 20.32 -7.62 0)
				(effects
					(font
						(size 1.27 1.27)
						(thickness 0.15)
					)
					(justify left bottom)
				)
			)
			(property "Tolerance" "1%"
				(at 20.32 -10.16 0)
				(effects
					(font
						(size 1.27 1.27)
					)
					(justify left bottom)
					(hide yes)
				)
			)
			(property "ki_keywords" "0402, SMT, RESISTOR, PASSIVE"
				(at 0 0 0)
				(effects
					(font
						(size 1.27 1.27)
					)
					(hide yes)
				)
			)
			(symbol "R_16k_0402_0_1"
				(rectangle
					(start 0.635 0.889)
					(end 4.445 -0.889)
					(stroke
						(width 0.254)
						(type default)
					)
					(fill
						(type none)
					)
				)
			)
			(symbol "R_16k_0402_1_1"
				(pin passive line
					(at 0 0 0)
					(length 0.635)
					(name "~"
						(effects
							(font
								(size 1.27 1.27)
							)
						)
					)
					(number "1"
						(effects
							(font
								(size 1.27 1.27)
							)
						)
					)
				)
				(pin passive line
					(at 5.08 0 180)
					(length 0.635)
					(name "~"
						(effects
							(font
								(size 1.27 1.27)
							)
						)
					)
					(number "2"
						(effects
							(font
								(size 1.27 1.27)
							)
						)
					)
				)
			)
		)
	(symbol "antmicroResistors0402:R_1k_0402"
			(pin_numbers
				(hide yes)
			)
			(pin_names
				(hide yes)
			)
			(exclude_from_sim no)
			(in_bom yes)
			(on_board yes)
			(property "Reference" "R"
				(at 20.32 -5.08 0)
				(effects
					(font
						(size 1.27 1.27)
						(thickness 0.15)
					)
					(justify left bottom)
				)
			)
			(property "Value" "R_1k_0402"
				(at 20.32 -12.7 0)
				(effects
					(font
						(size 1.27 1.27)
						(thickness 0.15)
					)
					(justify left bottom)
					(hide yes)
				)
			)
			(property "Footprint" "antmicro-footprints:R_0402_1005Metric"
				(at 20.32 -15.24 0)
				(effects
					(font
						(size 1.27 1.27)
						(thickness 0.15)
					)
					(justify left bottom)
					(hide yes)
				)
			)
			(property "Datasheet" "https://www.bourns.com/docs/product-datasheets/cr.pdf"
				(at 20.32 -17.78 0)
				(effects
					(font
						(size 1.27 1.27)
						(thickness 0.15)
					)
					(justify left bottom)
					(hide yes)
				)
			)
			(property "Description" "SMD Chip Resistor, 1 kohm, ± 1%, 63 mW, 0402 [1005 Metric], Thick Film, General Purpose"
				(at 20.32 -30.48 0)
				(effects
					(font
						(size 1.27 1.27)
					)
					(justify left bottom)
					(hide yes)
				)
			)
			(property "MPN" "CR0402-FX-1001GLF"
				(at 20.32 -20.32 0)
				(effects
					(font
						(size 1.27 1.27)
						(thickness 0.15)
					)
					(justify left bottom)
					(hide yes)
				)
			)
			(property "Manufacturer" "Bourns"
				(at 20.32 -22.86 0)
				(effects
					(font
						(size 1.27 1.27)
						(thickness 0.15)
					)
					(justify left bottom)
					(hide yes)
				)
			)
			(property "License" "Apache-2.0"
				(at 20.32 -25.4 0)
				(effects
					(font
						(size 1.27 1.27)
						(thickness 0.15)
					)
					(justify left bottom)
					(hide yes)
				)
			)
			(property "Author" "Antmicro"
				(at 20.32 -27.94 0)
				(effects
					(font
						(size 1.27 1.27)
						(thickness 0.15)
					)
					(justify left bottom)
					(hide yes)
				)
			)
			(property "Val" "1k"
				(at 20.32 -7.62 0)
				(effects
					(font
						(size 1.27 1.27)
						(thickness 0.15)
					)
					(justify left bottom)
				)
			)
			(property "Tolerance" "1%"
				(at 20.32 -10.16 0)
				(effects
					(font
						(size 1.27 1.27)
					)
					(justify left bottom)
					(hide yes)
				)
			)
			(property "ki_keywords" "0402, SMT, RESISTOR, PASSIVE"
				(at 0 0 0)
				(effects
					(font
						(size 1.27 1.27)
					)
					(hide yes)
				)
			)
			(symbol "R_1k_0402_0_1"
				(rectangle
					(start 0.635 0.889)
					(end 4.445 -0.889)
					(stroke
						(width 0.254)
						(type default)
					)
					(fill
						(type none)
					)
				)
			)
			(symbol "R_1k_0402_1_1"
				(pin passive line
					(at 0 0 0)
					(length 0.635)
					(name "~"
						(effects
							(font
								(size 1.27 1.27)
							)
						)
					)
					(number "1"
						(effects
							(font
								(size 1.27 1.27)
							)
						)
					)
				)
				(pin passive line
					(at 5.08 0 180)
					(length 0.635)
					(name "~"
						(effects
							(font
								(size 1.27 1.27)
							)
						)
					)
					(number "2"
						(effects
							(font
								(size 1.27 1.27)
							)
						)
					)
				)
			)
		)
	(symbol "antmicroResistors0402:R_20k_0402"
			(pin_numbers
				(hide yes)
			)
			(pin_names
				(hide yes)
			)
			(exclude_from_sim no)
			(in_bom yes)
			(on_board yes)
			(property "Reference" "R"
				(at 20.32 -5.08 0)
				(effects
					(font
						(size 1.27 1.27)
						(thickness 0.15)
					)
					(justify left bottom)
				)
			)
			(property "Value" "R_20k_0402"
				(at 20.32 -12.7 0)
				(effects
					(font
						(size 1.27 1.27)
						(thickness 0.15)
					)
					(justify left bottom)
					(hide yes)
				)
			)
			(property "Footprint" "antmicro-footprints:R_0402_1005Metric"
				(at 20.32 -15.24 0)
				(effects
					(font
						(size 1.27 1.27)
						(thickness 0.15)
					)
					(justify left bottom)
					(hide yes)
				)
			)
			(property "Datasheet" "https://www.bourns.com/docs/product-datasheets/cr.pdf"
				(at 20.32 -17.78 0)
				(effects
					(font
						(size 1.27 1.27)
						(thickness 0.15)
					)
					(justify left bottom)
					(hide yes)
				)
			)
			(property "Description" "SMD Chip Resistor, 20 kohm, ± 1%, 62.5 mW, 0402 [1005 Metric], Thick Film, General Purpose"
				(at 20.32 -30.48 0)
				(effects
					(font
						(size 1.27 1.27)
					)
					(justify left bottom)
					(hide yes)
				)
			)
			(property "MPN" "CR0402-FX-2002GLF"
				(at 20.32 -20.32 0)
				(effects
					(font
						(size 1.27 1.27)
						(thickness 0.15)
					)
					(justify left bottom)
					(hide yes)
				)
			)
			(property "Manufacturer" "Bourns"
				(at 20.32 -22.86 0)
				(effects
					(font
						(size 1.27 1.27)
						(thickness 0.15)
					)
					(justify left bottom)
					(hide yes)
				)
			)
			(property "License" "Apache-2.0"
				(at 20.32 -25.4 0)
				(effects
					(font
						(size 1.27 1.27)
						(thickness 0.15)
					)
					(justify left bottom)
					(hide yes)
				)
			)
			(property "Author" "Antmicro"
				(at 20.32 -27.94 0)
				(effects
					(font
						(size 1.27 1.27)
						(thickness 0.15)
					)
					(justify left bottom)
					(hide yes)
				)
			)
			(property "Val" "20k"
				(at 20.32 -7.62 0)
				(effects
					(font
						(size 1.27 1.27)
						(thickness 0.15)
					)
					(justify left bottom)
				)
			)
			(property "Tolerance" "1%"
				(at 20.32 -10.16 0)
				(effects
					(font
						(size 1.27 1.27)
					)
					(justify left bottom)
					(hide yes)
				)
			)
			(property "ki_keywords" "0402, SMT, RESISTOR, PASSIVE"
				(at 0 0 0)
				(effects
					(font
						(size 1.27 1.27)
					)
					(hide yes)
				)
			)
			(symbol "R_20k_0402_0_1"
				(rectangle
					(start 0.635 0.889)
					(end 4.445 -0.889)
					(stroke
						(width 0.254)
						(type default)
					)
					(fill
						(type none)
					)
				)
			)
			(symbol "R_20k_0402_1_1"
				(pin passive line
					(at 0 0 0)
					(length 0.635)
					(name "~"
						(effects
							(font
								(size 1.27 1.27)
							)
						)
					)
					(number "1"
						(effects
							(font
								(size 1.27 1.27)
							)
						)
					)
				)
				(pin passive line
					(at 5.08 0 180)
					(length 0.635)
					(name "~"
						(effects
							(font
								(size 1.27 1.27)
							)
						)
					)
					(number "2"
						(effects
							(font
								(size 1.27 1.27)
							)
						)
					)
				)
			)
		)
	(symbol "antmicroResistors0402:R_220R_0402"
			(pin_numbers
				(hide yes)
			)
			(pin_names
				(hide yes)
			)
			(exclude_from_sim no)
			(in_bom yes)
			(on_board yes)
			(property "Reference" "R"
				(at 20.32 -5.08 0)
				(effects
					(font
						(size 1.27 1.27)
						(thickness 0.15)
					)
					(justify left bottom)
				)
			)
			(property "Value" "R_220R_0402"
				(at 20.32 -12.7 0)
				(effects
					(font
						(size 1.27 1.27)
						(thickness 0.15)
					)
					(justify left bottom)
					(hide yes)
				)
			)
			(property "Footprint" "antmicro-footprints:R_0402_1005Metric"
				(at 20.32 -15.24 0)
				(effects
					(font
						(size 1.27 1.27)
						(thickness 0.15)
					)
					(justify left bottom)
					(hide yes)
				)
			)
			(property "Datasheet" "https://www.bourns.com/docs/product-datasheets/cr.pdf"
				(at 20.32 -17.78 0)
				(effects
					(font
						(size 1.27 1.27)
						(thickness 0.15)
					)
					(justify left bottom)
					(hide yes)
				)
			)
			(property "Description" "SMD Chip Resistor, 220 ohm, ± 1%, 62.5 mW, 0402 [1005 Metric], Thick Film, General Purpose"
				(at 20.32 -30.48 0)
				(effects
					(font
						(size 1.27 1.27)
					)
					(justify left bottom)
					(hide yes)
				)
			)
			(property "MPN" "CR0402-FX-2200GLF"
				(at 20.32 -20.32 0)
				(effects
					(font
						(size 1.27 1.27)
						(thickness 0.15)
					)
					(justify left bottom)
					(hide yes)
				)
			)
			(property "Manufacturer" "Bourns"
				(at 20.32 -22.86 0)
				(effects
					(font
						(size 1.27 1.27)
						(thickness 0.15)
					)
					(justify left bottom)
					(hide yes)
				)
			)
			(property "License" "Apache-2.0"
				(at 20.32 -25.4 0)
				(effects
					(font
						(size 1.27 1.27)
						(thickness 0.15)
					)
					(justify left bottom)
					(hide yes)
				)
			)
			(property "Author" "Antmicro"
				(at 20.32 -27.94 0)
				(effects
					(font
						(size 1.27 1.27)
						(thickness 0.15)
					)
					(justify left bottom)
					(hide yes)
				)
			)
			(property "Val" "220R"
				(at 20.32 -7.62 0)
				(effects
					(font
						(size 1.27 1.27)
						(thickness 0.15)
					)
					(justify left bottom)
				)
			)
			(property "Tolerance" "1%"
				(at 20.32 -10.16 0)
				(effects
					(font
						(size 1.27 1.27)
					)
					(justify left bottom)
					(hide yes)
				)
			)
			(property "ki_keywords" "0402, SMT, RESISTOR, PASSIVE"
				(at 0 0 0)
				(effects
					(font
						(size 1.27 1.27)
					)
					(hide yes)
				)
			)
			(symbol "R_220R_0402_0_1"
				(rectangle
					(start 0.635 0.889)
					(end 4.445 -0.889)
					(stroke
						(width 0.254)
						(type default)
					)
					(fill
						(type none)
					)
				)
			)
			(symbol "R_220R_0402_1_1"
				(pin passive line
					(at 0 0 0)
					(length 0.635)
					(name "~"
						(effects
							(font
								(size 1.27 1.27)
							)
						)
					)
					(number "1"
						(effects
							(font
								(size 1.27 1.27)
							)
						)
					)
				)
				(pin passive line
					(at 5.08 0 180)
					(length 0.635)
					(name "~"
						(effects
							(font
								(size 1.27 1.27)
							)
						)
					)
					(number "2"
						(effects
							(font
								(size 1.27 1.27)
							)
						)
					)
				)
			)
		)
	(symbol "antmicroResistors0402:R_22R_0402"
			(pin_numbers
				(hide yes)
			)
			(pin_names
				(hide yes)
			)
			(exclude_from_sim no)
			(in_bom yes)
			(on_board yes)
			(property "Reference" "R"
				(at 20.32 -5.08 0)
				(effects
					(font
						(size 1.27 1.27)
						(thickness 0.15)
					)
					(justify left bottom)
				)
			)
			(property "Value" "R_22R_0402"
				(at 20.32 -12.7 0)
				(effects
					(font
						(size 1.27 1.27)
						(thickness 0.15)
					)
					(justify left bottom)
					(hide yes)
				)
			)
			(property "Footprint" "antmicro-footprints:R_0402_1005Metric"
				(at 20.32 -15.24 0)
				(effects
					(font
						(size 1.27 1.27)
						(thickness 0.15)
					)
					(justify left bottom)
					(hide yes)
				)
			)
			(property "Datasheet" "https://www.bourns.com/docs/product-datasheets/cr.pdf"
				(at 20.32 -17.78 0)
				(effects
					(font
						(size 1.27 1.27)
						(thickness 0.15)
					)
					(justify left bottom)
					(hide yes)
				)
			)
			(property "Description" "SMD Chip Resistor, 22 ohm, ± 1%, 62.5 mW, 0402 [1005 Metric], Thick Film, General Purpose"
				(at 20.32 -30.48 0)
				(effects
					(font
						(size 1.27 1.27)
					)
					(justify left bottom)
					(hide yes)
				)
			)
			(property "MPN" "CR0402-FX-22R0GLF"
				(at 20.32 -20.32 0)
				(effects
					(font
						(size 1.27 1.27)
						(thickness 0.15)
					)
					(justify left bottom)
					(hide yes)
				)
			)
			(property "Manufacturer" "Bourns"
				(at 20.32 -22.86 0)
				(effects
					(font
						(size 1.27 1.27)
						(thickness 0.15)
					)
					(justify left bottom)
					(hide yes)
				)
			)
			(property "License" "Apache-2.0"
				(at 20.32 -25.4 0)
				(effects
					(font
						(size 1.27 1.27)
						(thickness 0.15)
					)
					(justify left bottom)
					(hide yes)
				)
			)
			(property "Author" "Antmicro"
				(at 20.32 -27.94 0)
				(effects
					(font
						(size 1.27 1.27)
						(thickness 0.15)
					)
					(justify left bottom)
					(hide yes)
				)
			)
			(property "Val" "22R"
				(at 20.32 -7.62 0)
				(effects
					(font
						(size 1.27 1.27)
						(thickness 0.15)
					)
					(justify left bottom)
				)
			)
			(property "Tolerance" "1%"
				(at 20.32 -10.16 0)
				(effects
					(font
						(size 1.27 1.27)
					)
					(justify left bottom)
					(hide yes)
				)
			)
			(property "ki_keywords" "0402, SMT, RESISTOR, PASSIVE"
				(at 0 0 0)
				(effects
					(font
						(size 1.27 1.27)
					)
					(hide yes)
				)
			)
			(symbol "R_22R_0402_0_1"
				(rectangle
					(start 0.635 0.889)
					(end 4.445 -0.889)
					(stroke
						(width 0.254)
						(type default)
					)
					(fill
						(type none)
					)
				)
			)
			(symbol "R_22R_0402_1_1"
				(pin passive line
					(at 0 0 0)
					(length 0.635)
					(name "~"
						(effects
							(font
								(size 1.27 1.27)
							)
						)
					)
					(number "1"
						(effects
							(font
								(size 1.27 1.27)
							)
						)
					)
				)
				(pin passive line
					(at 5.08 0 180)
					(length 0.635)
					(name "~"
						(effects
							(font
								(size 1.27 1.27)
							)
						)
					)
					(number "2"
						(effects
							(font
								(size 1.27 1.27)
							)
						)
					)
				)
			)
		)
	(symbol "antmicroResistors0402:R_255k_0402"
			(pin_numbers
				(hide yes)
			)
			(pin_names
				(hide yes)
			)
			(exclude_from_sim no)
			(in_bom yes)
			(on_board yes)
			(property "Reference" "R"
				(at 20.32 -5.08 0)
				(effects
					(font
						(size 1.27 1.27)
						(thickness 0.15)
					)
					(justify left bottom)
				)
			)
			(property "Value" "R_255k_0402"
				(at 20.32 -12.7 0)
				(effects
					(font
						(size 1.27 1.27)
						(thickness 0.15)
					)
					(justify left bottom)
					(hide yes)
				)
			)
			(property "Footprint" "antmicro-footprints:R_0402_1005Metric"
				(at 20.32 -15.24 0)
				(effects
					(font
						(size 1.27 1.27)
						(thickness 0.15)
					)
					(justify left bottom)
					(hide yes)
				)
			)
			(property "Datasheet" "https://www.bourns.com/docs/product-datasheets/cr.pdf"
				(at 20.32 -17.78 0)
				(effects
					(font
						(size 1.27 1.27)
						(thickness 0.15)
					)
					(justify left bottom)
					(hide yes)
				)
			)
			(property "Description" "SMD Chip Resistor, 255 kohm, ± 1%, 100 mW, 0402 [1005 Metric], Thick Film, Precision"
				(at 20.32 -30.48 0)
				(effects
					(font
						(size 1.27 1.27)
					)
					(justify left bottom)
					(hide yes)
				)
			)
			(property "MPN" "CR0402-FX-2553GLF"
				(at 20.32 -20.32 0)
				(effects
					(font
						(size 1.27 1.27)
						(thickness 0.15)
					)
					(justify left bottom)
					(hide yes)
				)
			)
			(property "Manufacturer" "Bourns"
				(at 20.32 -22.86 0)
				(effects
					(font
						(size 1.27 1.27)
						(thickness 0.15)
					)
					(justify left bottom)
					(hide yes)
				)
			)
			(property "License" "Apache-2.0"
				(at 20.32 -25.4 0)
				(effects
					(font
						(size 1.27 1.27)
						(thickness 0.15)
					)
					(justify left bottom)
					(hide yes)
				)
			)
			(property "Author" "Antmicro"
				(at 20.32 -27.94 0)
				(effects
					(font
						(size 1.27 1.27)
						(thickness 0.15)
					)
					(justify left bottom)
					(hide yes)
				)
			)
			(property "Val" "255k"
				(at 20.32 -7.62 0)
				(effects
					(font
						(size 1.27 1.27)
						(thickness 0.15)
					)
					(justify left bottom)
				)
			)
			(property "Tolerance" "1%"
				(at 20.32 -10.16 0)
				(effects
					(font
						(size 1.27 1.27)
					)
					(justify left bottom)
					(hide yes)
				)
			)
			(property "ki_keywords" "0402, SMT, RESISTOR, PASSIVE"
				(at 0 0 0)
				(effects
					(font
						(size 1.27 1.27)
					)
					(hide yes)
				)
			)
			(symbol "R_255k_0402_0_1"
				(rectangle
					(start 0.635 0.889)
					(end 4.445 -0.889)
					(stroke
						(width 0.254)
						(type default)
					)
					(fill
						(type none)
					)
				)
			)
			(symbol "R_255k_0402_1_1"
				(pin passive line
					(at 0 0 0)
					(length 0.635)
					(name "~"
						(effects
							(font
								(size 1.27 1.27)
							)
						)
					)
					(number "1"
						(effects
							(font
								(size 1.27 1.27)
							)
						)
					)
				)
				(pin passive line
					(at 5.08 0 180)
					(length 0.635)
					(name "~"
						(effects
							(font
								(size 1.27 1.27)
							)
						)
					)
					(number "2"
						(effects
							(font
								(size 1.27 1.27)
							)
						)
					)
				)
			)
		)
	(symbol "antmicroResistors0402:R_2k_0402"
			(pin_numbers
				(hide yes)
			)
			(pin_names
				(hide yes)
			)
			(exclude_from_sim no)
			(in_bom yes)
			(on_board yes)
			(property "Reference" "R"
				(at 20.32 -5.08 0)
				(effects
					(font
						(size 1.27 1.27)
						(thickness 0.15)
					)
					(justify left bottom)
				)
			)
			(property "Value" "R_2k_0402"
				(at 20.32 -12.7 0)
				(effects
					(font
						(size 1.27 1.27)
						(thickness 0.15)
					)
					(justify left bottom)
					(hide yes)
				)
			)
			(property "Footprint" "antmicro-footprints:R_0402_1005Metric"
				(at 20.32 -15.24 0)
				(effects
					(font
						(size 1.27 1.27)
						(thickness 0.15)
					)
					(justify left bottom)
					(hide yes)
				)
			)
			(property "Datasheet" "https://www.bourns.com/docs/product-datasheets/cr.pdf"
				(at 20.32 -17.78 0)
				(effects
					(font
						(size 1.27 1.27)
						(thickness 0.15)
					)
					(justify left bottom)
					(hide yes)
				)
			)
			(property "Description" "SMD Chip Resistor, 2 kohm, ± 1%, 62.5 mW, 0402 [1005 Metric], Thick Film, General Purpose"
				(at 20.32 -30.48 0)
				(effects
					(font
						(size 1.27 1.27)
					)
					(justify left bottom)
					(hide yes)
				)
			)
			(property "MPN" "CR0402-FX-2001GLF"
				(at 20.32 -20.32 0)
				(effects
					(font
						(size 1.27 1.27)
						(thickness 0.15)
					)
					(justify left bottom)
					(hide yes)
				)
			)
			(property "Manufacturer" "Bourns"
				(at 20.32 -22.86 0)
				(effects
					(font
						(size 1.27 1.27)
						(thickness 0.15)
					)
					(justify left bottom)
					(hide yes)
				)
			)
			(property "License" "Apache-2.0"
				(at 20.32 -25.4 0)
				(effects
					(font
						(size 1.27 1.27)
						(thickness 0.15)
					)
					(justify left bottom)
					(hide yes)
				)
			)
			(property "Author" "Antmicro"
				(at 20.32 -27.94 0)
				(effects
					(font
						(size 1.27 1.27)
						(thickness 0.15)
					)
					(justify left bottom)
					(hide yes)
				)
			)
			(property "Val" "2k"
				(at 20.32 -7.62 0)
				(effects
					(font
						(size 1.27 1.27)
						(thickness 0.15)
					)
					(justify left bottom)
				)
			)
			(property "Tolerance" "1%"
				(at 20.32 -10.16 0)
				(effects
					(font
						(size 1.27 1.27)
					)
					(justify left bottom)
					(hide yes)
				)
			)
			(property "ki_keywords" "0402, SMT, RESISTOR, PASSIVE"
				(at 0 0 0)
				(effects
					(font
						(size 1.27 1.27)
					)
					(hide yes)
				)
			)
			(symbol "R_2k_0402_0_1"
				(rectangle
					(start 0.635 0.889)
					(end 4.445 -0.889)
					(stroke
						(width 0.254)
						(type default)
					)
					(fill
						(type none)
					)
				)
			)
			(symbol "R_2k_0402_1_1"
				(pin passive line
					(at 0 0 0)
					(length 0.635)
					(name "~"
						(effects
							(font
								(size 1.27 1.27)
							)
						)
					)
					(number "1"
						(effects
							(font
								(size 1.27 1.27)
							)
						)
					)
				)
				(pin passive line
					(at 5.08 0 180)
					(length 0.635)
					(name "~"
						(effects
							(font
								(size 1.27 1.27)
							)
						)
					)
					(number "2"
						(effects
							(font
								(size 1.27 1.27)
							)
						)
					)
				)
			)
		)
	(symbol "antmicroResistors0402:R_300R_0402"
			(pin_numbers
				(hide yes)
			)
			(pin_names
				(hide yes)
			)
			(exclude_from_sim no)
			(in_bom yes)
			(on_board yes)
			(property "Reference" "R"
				(at 20.32 -5.08 0)
				(effects
					(font
						(size 1.27 1.27)
						(thickness 0.15)
					)
					(justify left bottom)
				)
			)
			(property "Value" "R_300R_0402"
				(at 20.32 -12.7 0)
				(effects
					(font
						(size 1.27 1.27)
						(thickness 0.15)
					)
					(justify left bottom)
					(hide yes)
				)
			)
			(property "Footprint" "antmicro-footprints:R_0402_1005Metric"
				(at 20.32 -15.24 0)
				(effects
					(font
						(size 1.27 1.27)
						(thickness 0.15)
					)
					(justify left bottom)
					(hide yes)
				)
			)
			(property "Datasheet" "https://www.farnell.com/datasheets/3795017.pdf"
				(at 20.32 -17.78 0)
				(effects
					(font
						(size 1.27 1.27)
						(thickness 0.15)
					)
					(justify left bottom)
					(hide yes)
				)
			)
			(property "Description" "MULTICOMP PRO MCMR04X3000FTLSMD Chip Resistor, Ceramic, 300 ohm, ± 1%, 62.5 mW, 0402 [1005 Metric], Thick Film"
				(at 20.32 -30.48 0)
				(effects
					(font
						(size 1.27 1.27)
					)
					(justify left bottom)
					(hide yes)
				)
			)
			(property "MPN" "RMCF0402FT300R"
				(at 20.32 -20.32 0)
				(effects
					(font
						(size 1.27 1.27)
						(thickness 0.15)
					)
					(justify left bottom)
					(hide yes)
				)
			)
			(property "Manufacturer" "Stackpole Electronics"
				(at 20.32 -22.86 0)
				(effects
					(font
						(size 1.27 1.27)
						(thickness 0.15)
					)
					(justify left bottom)
					(hide yes)
				)
			)
			(property "License" "Apache-2.0"
				(at 20.32 -25.4 0)
				(effects
					(font
						(size 1.27 1.27)
						(thickness 0.15)
					)
					(justify left bottom)
					(hide yes)
				)
			)
			(property "Author" "Antmicro"
				(at 20.32 -27.94 0)
				(effects
					(font
						(size 1.27 1.27)
						(thickness 0.15)
					)
					(justify left bottom)
					(hide yes)
				)
			)
			(property "Val" "300R"
				(at 20.32 -7.62 0)
				(effects
					(font
						(size 1.27 1.27)
						(thickness 0.15)
					)
					(justify left bottom)
				)
			)
			(property "Tolerance" "1%"
				(at 20.32 -10.16 0)
				(effects
					(font
						(size 1.27 1.27)
					)
					(justify left bottom)
					(hide yes)
				)
			)
			(property "ki_keywords" "0402, SMT, RESISTOR, PASSIVE"
				(at 0 0 0)
				(effects
					(font
						(size 1.27 1.27)
					)
					(hide yes)
				)
			)
			(symbol "R_300R_0402_0_1"
				(rectangle
					(start 0.635 0.889)
					(end 4.445 -0.889)
					(stroke
						(width 0.254)
						(type default)
					)
					(fill
						(type none)
					)
				)
			)
			(symbol "R_300R_0402_1_1"
				(pin passive line
					(at 0 0 0)
					(length 0.635)
					(name "~"
						(effects
							(font
								(size 1.27 1.27)
							)
						)
					)
					(number "1"
						(effects
							(font
								(size 1.27 1.27)
							)
						)
					)
				)
				(pin passive line
					(at 5.08 0 180)
					(length 0.635)
					(name "~"
						(effects
							(font
								(size 1.27 1.27)
							)
						)
					)
					(number "2"
						(effects
							(font
								(size 1.27 1.27)
							)
						)
					)
				)
			)
		)
	(symbol "antmicroResistors0402:R_30k_0402"
			(pin_numbers
				(hide yes)
			)
			(pin_names
				(hide yes)
			)
			(exclude_from_sim no)
			(in_bom yes)
			(on_board yes)
			(property "Reference" "R"
				(at 20.32 -5.08 0)
				(effects
					(font
						(size 1.27 1.27)
						(thickness 0.15)
					)
					(justify left bottom)
				)
			)
			(property "Value" "R_30k_0402"
				(at 20.32 -12.7 0)
				(effects
					(font
						(size 1.27 1.27)
						(thickness 0.15)
					)
					(justify left bottom)
					(hide yes)
				)
			)
			(property "Footprint" "antmicro-footprints:R_0402_1005Metric"
				(at 20.32 -15.24 0)
				(effects
					(font
						(size 1.27 1.27)
						(thickness 0.15)
					)
					(justify left bottom)
					(hide yes)
				)
			)
			(property "Datasheet" "https://www.bourns.com/docs/product-datasheets/cr.pdf"
				(at 20.32 -17.78 0)
				(effects
					(font
						(size 1.27 1.27)
						(thickness 0.15)
					)
					(justify left bottom)
					(hide yes)
				)
			)
			(property "Description" "SMD Chip Resistor, 30 kohm, ± 1%, 63 mW, 0402 [1005 Metric], Thick Film, General Purpose"
				(at 20.32 -30.48 0)
				(effects
					(font
						(size 1.27 1.27)
					)
					(justify left bottom)
					(hide yes)
				)
			)
			(property "MPN" "CR0402-FX-3002GLF"
				(at 20.32 -20.32 0)
				(effects
					(font
						(size 1.27 1.27)
						(thickness 0.15)
					)
					(justify left bottom)
					(hide yes)
				)
			)
			(property "Manufacturer" "Bourns"
				(at 20.32 -22.86 0)
				(effects
					(font
						(size 1.27 1.27)
						(thickness 0.15)
					)
					(justify left bottom)
					(hide yes)
				)
			)
			(property "License" "Apache-2.0"
				(at 20.32 -25.4 0)
				(effects
					(font
						(size 1.27 1.27)
						(thickness 0.15)
					)
					(justify left bottom)
					(hide yes)
				)
			)
			(property "Author" "Antmicro"
				(at 20.32 -27.94 0)
				(effects
					(font
						(size 1.27 1.27)
						(thickness 0.15)
					)
					(justify left bottom)
					(hide yes)
				)
			)
			(property "Val" "30k"
				(at 20.32 -7.62 0)
				(effects
					(font
						(size 1.27 1.27)
						(thickness 0.15)
					)
					(justify left bottom)
				)
			)
			(property "Tolerance" "1%"
				(at 20.32 -10.16 0)
				(effects
					(font
						(size 1.27 1.27)
					)
					(justify left bottom)
					(hide yes)
				)
			)
			(property "ki_keywords" "0402, SMT, RESISTOR, PASSIVE"
				(at 0 0 0)
				(effects
					(font
						(size 1.27 1.27)
					)
					(hide yes)
				)
			)
			(symbol "R_30k_0402_0_1"
				(rectangle
					(start 0.635 0.889)
					(end 4.445 -0.889)
					(stroke
						(width 0.254)
						(type default)
					)
					(fill
						(type none)
					)
				)
			)
			(symbol "R_30k_0402_1_1"
				(pin passive line
					(at 0 0 0)
					(length 0.635)
					(name "~"
						(effects
							(font
								(size 1.27 1.27)
							)
						)
					)
					(number "1"
						(effects
							(font
								(size 1.27 1.27)
							)
						)
					)
				)
				(pin passive line
					(at 5.08 0 180)
					(length 0.635)
					(name "~"
						(effects
							(font
								(size 1.27 1.27)
							)
						)
					)
					(number "2"
						(effects
							(font
								(size 1.27 1.27)
							)
						)
					)
				)
			)
		)
	(symbol "antmicroResistors0402:R_33R_0402"
			(pin_numbers
				(hide yes)
			)
			(pin_names
				(hide yes)
			)
			(exclude_from_sim no)
			(in_bom yes)
			(on_board yes)
			(property "Reference" "R"
				(at 20.32 -5.08 0)
				(effects
					(font
						(size 1.27 1.27)
						(thickness 0.15)
					)
					(justify left bottom)
				)
			)
			(property "Value" "R_33R_0402"
				(at 20.32 -12.7 0)
				(effects
					(font
						(size 1.27 1.27)
						(thickness 0.15)
					)
					(justify left bottom)
					(hide yes)
				)
			)
			(property "Footprint" "antmicro-footprints:R_0402_1005Metric"
				(at 20.32 -15.24 0)
				(effects
					(font
						(size 1.27 1.27)
						(thickness 0.15)
					)
					(justify left bottom)
					(hide yes)
				)
			)
			(property "Datasheet" "https://www.bourns.com/docs/product-datasheets/cr.pdf"
				(at 20.32 -17.78 0)
				(effects
					(font
						(size 1.27 1.27)
						(thickness 0.15)
					)
					(justify left bottom)
					(hide yes)
				)
			)
			(property "Description" "SMD Chip Resistor, 33 ohm, ± 1%, 62.5 mW, 0402 [1005 Metric], Thick Film, General Purpose"
				(at 20.32 -30.48 0)
				(effects
					(font
						(size 1.27 1.27)
					)
					(justify left bottom)
					(hide yes)
				)
			)
			(property "MPN" "CR0402-FX-33R0GLF"
				(at 20.32 -20.32 0)
				(effects
					(font
						(size 1.27 1.27)
						(thickness 0.15)
					)
					(justify left bottom)
					(hide yes)
				)
			)
			(property "Manufacturer" "Bourns"
				(at 20.32 -22.86 0)
				(effects
					(font
						(size 1.27 1.27)
						(thickness 0.15)
					)
					(justify left bottom)
					(hide yes)
				)
			)
			(property "License" "Apache-2.0"
				(at 20.32 -25.4 0)
				(effects
					(font
						(size 1.27 1.27)
						(thickness 0.15)
					)
					(justify left bottom)
					(hide yes)
				)
			)
			(property "Author" "Antmicro"
				(at 20.32 -27.94 0)
				(effects
					(font
						(size 1.27 1.27)
						(thickness 0.15)
					)
					(justify left bottom)
					(hide yes)
				)
			)
			(property "Val" "33R"
				(at 20.32 -7.62 0)
				(effects
					(font
						(size 1.27 1.27)
						(thickness 0.15)
					)
					(justify left bottom)
				)
			)
			(property "Tolerance" "1%"
				(at 20.32 -10.16 0)
				(effects
					(font
						(size 1.27 1.27)
					)
					(justify left bottom)
					(hide yes)
				)
			)
			(property "ki_keywords" "0402, SMT, RESISTOR, PASSIVE"
				(at 0 0 0)
				(effects
					(font
						(size 1.27 1.27)
					)
					(hide yes)
				)
			)
			(symbol "R_33R_0402_0_1"
				(rectangle
					(start 0.635 0.889)
					(end 4.445 -0.889)
					(stroke
						(width 0.254)
						(type default)
					)
					(fill
						(type none)
					)
				)
			)
			(symbol "R_33R_0402_1_1"
				(pin passive line
					(at 0 0 0)
					(length 0.635)
					(name "~"
						(effects
							(font
								(size 1.27 1.27)
							)
						)
					)
					(number "1"
						(effects
							(font
								(size 1.27 1.27)
							)
						)
					)
				)
				(pin passive line
					(at 5.08 0 180)
					(length 0.635)
					(name "~"
						(effects
							(font
								(size 1.27 1.27)
							)
						)
					)
					(number "2"
						(effects
							(font
								(size 1.27 1.27)
							)
						)
					)
				)
			)
		)
	(symbol "antmicroResistors0402:R_3k3_0402"
			(pin_numbers
				(hide yes)
			)
			(pin_names
				(hide yes)
			)
			(exclude_from_sim no)
			(in_bom yes)
			(on_board yes)
			(property "Reference" "R"
				(at 20.32 -5.08 0)
				(effects
					(font
						(size 1.27 1.27)
						(thickness 0.15)
					)
					(justify left bottom)
				)
			)
			(property "Value" "R_3k3_0402"
				(at 20.32 -12.7 0)
				(effects
					(font
						(size 1.27 1.27)
						(thickness 0.15)
					)
					(justify left bottom)
					(hide yes)
				)
			)
			(property "Footprint" "antmicro-footprints:R_0402_1005Metric"
				(at 20.32 -15.24 0)
				(effects
					(font
						(size 1.27 1.27)
						(thickness 0.15)
					)
					(justify left bottom)
					(hide yes)
				)
			)
			(property "Datasheet" "https://www.bourns.com/docs/product-datasheets/cr.pdf"
				(at 20.32 -17.78 0)
				(effects
					(font
						(size 1.27 1.27)
						(thickness 0.15)
					)
					(justify left bottom)
					(hide yes)
				)
			)
			(property "Description" "SMD Chip Resistor, 3.3 kohm, ± 1%, 63 mW, 0402 [1005 Metric], Thick Film, General Purpose"
				(at 20.32 -30.48 0)
				(effects
					(font
						(size 1.27 1.27)
					)
					(justify left bottom)
					(hide yes)
				)
			)
			(property "MPN" "CR0402-FX-3301GLF"
				(at 20.32 -20.32 0)
				(effects
					(font
						(size 1.27 1.27)
						(thickness 0.15)
					)
					(justify left bottom)
					(hide yes)
				)
			)
			(property "Manufacturer" "Bourns"
				(at 20.32 -22.86 0)
				(effects
					(font
						(size 1.27 1.27)
						(thickness 0.15)
					)
					(justify left bottom)
					(hide yes)
				)
			)
			(property "License" "Apache-2.0"
				(at 20.32 -25.4 0)
				(effects
					(font
						(size 1.27 1.27)
						(thickness 0.15)
					)
					(justify left bottom)
					(hide yes)
				)
			)
			(property "Author" "Antmicro"
				(at 20.32 -27.94 0)
				(effects
					(font
						(size 1.27 1.27)
						(thickness 0.15)
					)
					(justify left bottom)
					(hide yes)
				)
			)
			(property "Val" "3k3"
				(at 20.32 -7.62 0)
				(effects
					(font
						(size 1.27 1.27)
						(thickness 0.15)
					)
					(justify left bottom)
				)
			)
			(property "Tolerance" "1%"
				(at 20.32 -10.16 0)
				(effects
					(font
						(size 1.27 1.27)
					)
					(justify left bottom)
					(hide yes)
				)
			)
			(property "ki_keywords" "0402, SMT, RESISTOR, PASSIVE"
				(at 0 0 0)
				(effects
					(font
						(size 1.27 1.27)
					)
					(hide yes)
				)
			)
			(symbol "R_3k3_0402_0_1"
				(rectangle
					(start 0.635 0.889)
					(end 4.445 -0.889)
					(stroke
						(width 0.254)
						(type default)
					)
					(fill
						(type none)
					)
				)
			)
			(symbol "R_3k3_0402_1_1"
				(pin passive line
					(at 0 0 0)
					(length 0.635)
					(name "~"
						(effects
							(font
								(size 1.27 1.27)
							)
						)
					)
					(number "1"
						(effects
							(font
								(size 1.27 1.27)
							)
						)
					)
				)
				(pin passive line
					(at 5.08 0 180)
					(length 0.635)
					(name "~"
						(effects
							(font
								(size 1.27 1.27)
							)
						)
					)
					(number "2"
						(effects
							(font
								(size 1.27 1.27)
							)
						)
					)
				)
			)
		)
	(symbol "antmicroResistors0402:R_49R9_0402"
			(pin_numbers
				(hide yes)
			)
			(pin_names
				(hide yes)
			)
			(exclude_from_sim no)
			(in_bom yes)
			(on_board yes)
			(property "Reference" "R"
				(at 20.32 -5.08 0)
				(effects
					(font
						(size 1.27 1.27)
						(thickness 0.15)
					)
					(justify left bottom)
				)
			)
			(property "Value" "R_49R9_0402"
				(at 20.32 -12.7 0)
				(effects
					(font
						(size 1.27 1.27)
						(thickness 0.15)
					)
					(justify left bottom)
					(hide yes)
				)
			)
			(property "Footprint" "antmicro-footprints:R_0402_1005Metric"
				(at 20.32 -15.24 0)
				(effects
					(font
						(size 1.27 1.27)
						(thickness 0.15)
					)
					(justify left bottom)
					(hide yes)
				)
			)
			(property "Datasheet" "https://www.bourns.com/docs/product-datasheets/cr.pdf"
				(at 20.32 -17.78 0)
				(effects
					(font
						(size 1.27 1.27)
						(thickness 0.15)
					)
					(justify left bottom)
					(hide yes)
				)
			)
			(property "Description" "SMD Chip Resistor, 49.9 ohm, ± 1%, 62.5 mW, 0402 [1005 Metric], Thick Film, General Purpose"
				(at 20.32 -30.48 0)
				(effects
					(font
						(size 1.27 1.27)
					)
					(justify left bottom)
					(hide yes)
				)
			)
			(property "MPN" "CR0402-FX-49R9GLF"
				(at 20.32 -20.32 0)
				(effects
					(font
						(size 1.27 1.27)
						(thickness 0.15)
					)
					(justify left bottom)
					(hide yes)
				)
			)
			(property "Manufacturer" "Bourns"
				(at 20.32 -22.86 0)
				(effects
					(font
						(size 1.27 1.27)
						(thickness 0.15)
					)
					(justify left bottom)
					(hide yes)
				)
			)
			(property "License" "Apache-2.0"
				(at 20.32 -25.4 0)
				(effects
					(font
						(size 1.27 1.27)
						(thickness 0.15)
					)
					(justify left bottom)
					(hide yes)
				)
			)
			(property "Author" "Antmicro"
				(at 20.32 -27.94 0)
				(effects
					(font
						(size 1.27 1.27)
						(thickness 0.15)
					)
					(justify left bottom)
					(hide yes)
				)
			)
			(property "Val" "49R9"
				(at 20.32 -7.62 0)
				(effects
					(font
						(size 1.27 1.27)
						(thickness 0.15)
					)
					(justify left bottom)
				)
			)
			(property "Tolerance" "1%"
				(at 20.32 -10.16 0)
				(effects
					(font
						(size 1.27 1.27)
					)
					(justify left bottom)
					(hide yes)
				)
			)
			(property "ki_keywords" "0402, SMT, RESISTOR, PASSIVE"
				(at 0 0 0)
				(effects
					(font
						(size 1.27 1.27)
					)
					(hide yes)
				)
			)
			(symbol "R_49R9_0402_0_1"
				(rectangle
					(start 0.635 0.889)
					(end 4.445 -0.889)
					(stroke
						(width 0.254)
						(type default)
					)
					(fill
						(type none)
					)
				)
			)
			(symbol "R_49R9_0402_1_1"
				(pin passive line
					(at 0 0 0)
					(length 0.635)
					(name "~"
						(effects
							(font
								(size 1.27 1.27)
							)
						)
					)
					(number "1"
						(effects
							(font
								(size 1.27 1.27)
							)
						)
					)
				)
				(pin passive line
					(at 5.08 0 180)
					(length 0.635)
					(name "~"
						(effects
							(font
								(size 1.27 1.27)
							)
						)
					)
					(number "2"
						(effects
							(font
								(size 1.27 1.27)
							)
						)
					)
				)
			)
		)
	(symbol "antmicroResistors0402:R_4k53_0402"
			(pin_numbers
				(hide yes)
			)
			(pin_names
				(hide yes)
			)
			(exclude_from_sim no)
			(in_bom yes)
			(on_board yes)
			(property "Reference" "R"
				(at 20.32 -5.08 0)
				(effects
					(font
						(size 1.27 1.27)
						(thickness 0.15)
					)
					(justify left bottom)
				)
			)
			(property "Value" "R_4k53_0402"
				(at 20.32 -12.7 0)
				(effects
					(font
						(size 1.27 1.27)
						(thickness 0.15)
					)
					(justify left bottom)
					(hide yes)
				)
			)
			(property "Footprint" "antmicro-footprints:R_0402_1005Metric"
				(at 20.32 -15.24 0)
				(effects
					(font
						(size 1.27 1.27)
						(thickness 0.15)
					)
					(justify left bottom)
					(hide yes)
				)
			)
			(property "Datasheet" "https://industrial.panasonic.com/cdbs/www-data/pdf/RDM0000/AOA0000C307.pdf"
				(at 20.32 -17.78 0)
				(effects
					(font
						(size 1.27 1.27)
						(thickness 0.15)
					)
					(justify left bottom)
					(hide yes)
				)
			)
			(property "Description" "SMD Chip Resistor, 4.53 kohm, ± 0.1%, 62.5 mW, 0402 [1005 Metric], Automotive AEC-Q200 Thin Film"
				(at 20.32 -30.48 0)
				(effects
					(font
						(size 1.27 1.27)
					)
					(justify left bottom)
					(hide yes)
				)
			)
			(property "MPN" "ERA-2AEB4531X"
				(at 20.32 -20.32 0)
				(effects
					(font
						(size 1.27 1.27)
						(thickness 0.15)
					)
					(justify left bottom)
					(hide yes)
				)
			)
			(property "Manufacturer" "Panasonic"
				(at 20.32 -22.86 0)
				(effects
					(font
						(size 1.27 1.27)
						(thickness 0.15)
					)
					(justify left bottom)
					(hide yes)
				)
			)
			(property "License" "Apache-2.0"
				(at 20.32 -25.4 0)
				(effects
					(font
						(size 1.27 1.27)
						(thickness 0.15)
					)
					(justify left bottom)
					(hide yes)
				)
			)
			(property "Author" "Antmicro"
				(at 20.32 -27.94 0)
				(effects
					(font
						(size 1.27 1.27)
						(thickness 0.15)
					)
					(justify left bottom)
					(hide yes)
				)
			)
			(property "Val" "4k53"
				(at 20.32 -7.62 0)
				(effects
					(font
						(size 1.27 1.27)
						(thickness 0.15)
					)
					(justify left bottom)
				)
			)
			(property "Tolerance" "0.1%"
				(at 20.32 -10.16 0)
				(effects
					(font
						(size 1.27 1.27)
					)
					(justify left bottom)
				)
			)
			(property "ki_keywords" "0402, SMT, RESISTOR, PASSIVE"
				(at 0 0 0)
				(effects
					(font
						(size 1.27 1.27)
					)
					(hide yes)
				)
			)
			(symbol "R_4k53_0402_0_1"
				(rectangle
					(start 0.635 0.889)
					(end 4.445 -0.889)
					(stroke
						(width 0.254)
						(type default)
					)
					(fill
						(type none)
					)
				)
			)
			(symbol "R_4k53_0402_1_1"
				(pin passive line
					(at 0 0 0)
					(length 0.635)
					(name "~"
						(effects
							(font
								(size 1.27 1.27)
							)
						)
					)
					(number "1"
						(effects
							(font
								(size 1.27 1.27)
							)
						)
					)
				)
				(pin passive line
					(at 5.08 0 180)
					(length 0.635)
					(name "~"
						(effects
							(font
								(size 1.27 1.27)
							)
						)
					)
					(number "2"
						(effects
							(font
								(size 1.27 1.27)
							)
						)
					)
				)
			)
		)
	(symbol "antmicroResistors0402:R_4k75_0.5%_0402"
			(pin_numbers
				(hide yes)
			)
			(pin_names
				(hide yes)
			)
			(exclude_from_sim no)
			(in_bom yes)
			(on_board yes)
			(property "Reference" "R"
				(at 20.32 -5.08 0)
				(effects
					(font
						(size 1.27 1.27)
						(thickness 0.15)
					)
					(justify left bottom)
				)
			)
			(property "Value" "R_4k75_0.5%_0402"
				(at 20.32 -12.7 0)
				(effects
					(font
						(size 1.27 1.27)
						(thickness 0.15)
					)
					(justify left bottom)
					(hide yes)
				)
			)
			(property "Footprint" "antmicro-footprints:R_0402_1005Metric"
				(at 20.32 -15.24 0)
				(effects
					(font
						(size 1.27 1.27)
						(thickness 0.15)
					)
					(justify left bottom)
					(hide yes)
				)
			)
			(property "Datasheet" "https://industrial.panasonic.com/cdbs/www-data/pdf/RDQ0000/ast-ind-151033.pdf"
				(at 20.32 -17.78 0)
				(effects
					(font
						(size 1.27 1.27)
						(thickness 0.15)
					)
					(justify left bottom)
					(hide yes)
				)
			)
			(property "Description" "SMD Chip Resistor, 4.75 kohm, ± 0.5%, 100 mW, 0402 [1005 Metric], Thick Film, High Temperature"
				(at 20.32 -30.48 0)
				(effects
					(font
						(size 1.27 1.27)
					)
					(justify left bottom)
					(hide yes)
				)
			)
			(property "MPN" "ERJ-H2RD4751X"
				(at 20.32 -20.32 0)
				(effects
					(font
						(size 1.27 1.27)
						(thickness 0.15)
					)
					(justify left bottom)
					(hide yes)
				)
			)
			(property "Manufacturer" "Panasonic"
				(at 20.32 -22.86 0)
				(effects
					(font
						(size 1.27 1.27)
						(thickness 0.15)
					)
					(justify left bottom)
					(hide yes)
				)
			)
			(property "License" "Apache-2.0"
				(at 20.32 -25.4 0)
				(effects
					(font
						(size 1.27 1.27)
						(thickness 0.15)
					)
					(justify left bottom)
					(hide yes)
				)
			)
			(property "Author" "Antmicro"
				(at 20.32 -27.94 0)
				(effects
					(font
						(size 1.27 1.27)
						(thickness 0.15)
					)
					(justify left bottom)
					(hide yes)
				)
			)
			(property "Val" "4k75"
				(at 20.32 -7.62 0)
				(effects
					(font
						(size 1.27 1.27)
						(thickness 0.15)
					)
					(justify left bottom)
				)
			)
			(property "Tolerance" "0.5%"
				(at 20.32 -10.16 0)
				(effects
					(font
						(size 1.27 1.27)
					)
					(justify left bottom)
					(hide yes)
				)
			)
			(property "ki_keywords" "0402, SMT, RESISTOR, PASSIVE"
				(at 0 0 0)
				(effects
					(font
						(size 1.27 1.27)
					)
					(hide yes)
				)
			)
			(symbol "R_4k75_0.5%_0402_0_1"
				(rectangle
					(start 0.635 0.889)
					(end 4.445 -0.889)
					(stroke
						(width 0.254)
						(type default)
					)
					(fill
						(type none)
					)
				)
			)
			(symbol "R_4k75_0.5%_0402_1_1"
				(pin passive line
					(at 0 0 0)
					(length 0.635)
					(name "~"
						(effects
							(font
								(size 1.27 1.27)
							)
						)
					)
					(number "1"
						(effects
							(font
								(size 1.27 1.27)
							)
						)
					)
				)
				(pin passive line
					(at 5.08 0 180)
					(length 0.635)
					(name "~"
						(effects
							(font
								(size 1.27 1.27)
							)
						)
					)
					(number "2"
						(effects
							(font
								(size 1.27 1.27)
							)
						)
					)
				)
			)
		)
	(symbol "antmicroResistors0402:R_5k1_0402"
			(pin_numbers
				(hide yes)
			)
			(pin_names
				(hide yes)
			)
			(exclude_from_sim no)
			(in_bom yes)
			(on_board yes)
			(property "Reference" "R"
				(at 20.32 -5.08 0)
				(effects
					(font
						(size 1.27 1.27)
						(thickness 0.15)
					)
					(justify left bottom)
				)
			)
			(property "Value" "R_5k1_0402"
				(at 20.32 -12.7 0)
				(effects
					(font
						(size 1.27 1.27)
						(thickness 0.15)
					)
					(justify left bottom)
					(hide yes)
				)
			)
			(property "Footprint" "antmicro-footprints:R_0402_1005Metric"
				(at 20.32 -15.24 0)
				(effects
					(font
						(size 1.27 1.27)
						(thickness 0.15)
					)
					(justify left bottom)
					(hide yes)
				)
			)
			(property "Datasheet" "https://www.bourns.com/docs/product-datasheets/cr.pdf"
				(at 20.32 -17.78 0)
				(effects
					(font
						(size 1.27 1.27)
						(thickness 0.15)
					)
					(justify left bottom)
					(hide yes)
				)
			)
			(property "Description" "SMD Chip Resistor, 5.1 kohm, ± 1%, 63 mW, 0402 [1005 Metric], Thick Film, General Purpose"
				(at 20.32 -30.48 0)
				(effects
					(font
						(size 1.27 1.27)
					)
					(justify left bottom)
					(hide yes)
				)
			)
			(property "MPN" "CR0402-FX-5101GLF"
				(at 20.32 -20.32 0)
				(effects
					(font
						(size 1.27 1.27)
						(thickness 0.15)
					)
					(justify left bottom)
					(hide yes)
				)
			)
			(property "Manufacturer" "Bourns"
				(at 20.32 -22.86 0)
				(effects
					(font
						(size 1.27 1.27)
						(thickness 0.15)
					)
					(justify left bottom)
					(hide yes)
				)
			)
			(property "License" "Apache-2.0"
				(at 20.32 -25.4 0)
				(effects
					(font
						(size 1.27 1.27)
						(thickness 0.15)
					)
					(justify left bottom)
					(hide yes)
				)
			)
			(property "Author" "Antmicro"
				(at 20.32 -27.94 0)
				(effects
					(font
						(size 1.27 1.27)
						(thickness 0.15)
					)
					(justify left bottom)
					(hide yes)
				)
			)
			(property "Val" "5k1"
				(at 20.32 -7.62 0)
				(effects
					(font
						(size 1.27 1.27)
						(thickness 0.15)
					)
					(justify left bottom)
				)
			)
			(property "Tolerance" "1%"
				(at 20.32 -10.16 0)
				(effects
					(font
						(size 1.27 1.27)
					)
					(justify left bottom)
					(hide yes)
				)
			)
			(property "ki_keywords" "0402, SMT, RESISTOR, PASSIVE"
				(at 0 0 0)
				(effects
					(font
						(size 1.27 1.27)
					)
					(hide yes)
				)
			)
			(symbol "R_5k1_0402_0_1"
				(rectangle
					(start 0.635 0.889)
					(end 4.445 -0.889)
					(stroke
						(width 0.254)
						(type default)
					)
					(fill
						(type none)
					)
				)
			)
			(symbol "R_5k1_0402_1_1"
				(pin passive line
					(at 0 0 0)
					(length 0.635)
					(name "~"
						(effects
							(font
								(size 1.27 1.27)
							)
						)
					)
					(number "1"
						(effects
							(font
								(size 1.27 1.27)
							)
						)
					)
				)
				(pin passive line
					(at 5.08 0 180)
					(length 0.635)
					(name "~"
						(effects
							(font
								(size 1.27 1.27)
							)
						)
					)
					(number "2"
						(effects
							(font
								(size 1.27 1.27)
							)
						)
					)
				)
			)
		)
	(symbol "antmicroResistors0402:R_63k4_0402"
			(pin_numbers
				(hide yes)
			)
			(pin_names
				(hide yes)
			)
			(exclude_from_sim no)
			(in_bom yes)
			(on_board yes)
			(property "Reference" "R"
				(at 20.32 -5.08 0)
				(effects
					(font
						(size 1.27 1.27)
						(thickness 0.15)
					)
					(justify left bottom)
				)
			)
			(property "Value" "R_63k4_0402"
				(at 20.32 -12.7 0)
				(effects
					(font
						(size 1.27 1.27)
						(thickness 0.15)
					)
					(justify left bottom)
					(hide yes)
				)
			)
			(property "Footprint" "antmicro-footprints:R_0402_1005Metric"
				(at 20.32 -15.24 0)
				(effects
					(font
						(size 1.27 1.27)
						(thickness 0.15)
					)
					(justify left bottom)
					(hide yes)
				)
			)
			(property "Datasheet" "https://industrial.panasonic.com/cdbs/www-data/pdf/RDM0000/AOA0000C307.pdf"
				(at 20.32 -17.78 0)
				(effects
					(font
						(size 1.27 1.27)
						(thickness 0.15)
					)
					(justify left bottom)
					(hide yes)
				)
			)
			(property "Description" "SMD Chip Resistor, 63.4 kohm, ± 0.1%, 63 mW, 0402 [1005 Metric], Thin Film,  Precision"
				(at 20.32 -30.48 0)
				(effects
					(font
						(size 1.27 1.27)
					)
					(justify left bottom)
					(hide yes)
				)
			)
			(property "MPN" "ERA-2AEB6342X"
				(at 20.32 -20.32 0)
				(effects
					(font
						(size 1.27 1.27)
						(thickness 0.15)
					)
					(justify left bottom)
					(hide yes)
				)
			)
			(property "Manufacturer" "Panasonic"
				(at 20.32 -22.86 0)
				(effects
					(font
						(size 1.27 1.27)
						(thickness 0.15)
					)
					(justify left bottom)
					(hide yes)
				)
			)
			(property "License" "Apache-2.0"
				(at 20.32 -25.4 0)
				(effects
					(font
						(size 1.27 1.27)
						(thickness 0.15)
					)
					(justify left bottom)
					(hide yes)
				)
			)
			(property "Author" "Antmicro"
				(at 20.32 -27.94 0)
				(effects
					(font
						(size 1.27 1.27)
						(thickness 0.15)
					)
					(justify left bottom)
					(hide yes)
				)
			)
			(property "Val" "63k4"
				(at 20.32 -7.62 0)
				(effects
					(font
						(size 1.27 1.27)
						(thickness 0.15)
					)
					(justify left bottom)
				)
			)
			(property "Tolerance" "0.1%"
				(at 20.32 -10.16 0)
				(effects
					(font
						(size 1.27 1.27)
					)
					(justify left bottom)
					(hide yes)
				)
			)
			(property "ki_keywords" "0402, SMT, RESISTOR, PASSIVE"
				(at 0 0 0)
				(effects
					(font
						(size 1.27 1.27)
					)
					(hide yes)
				)
			)
			(symbol "R_63k4_0402_0_1"
				(rectangle
					(start 0.635 0.889)
					(end 4.445 -0.889)
					(stroke
						(width 0.254)
						(type default)
					)
					(fill
						(type none)
					)
				)
			)
			(symbol "R_63k4_0402_1_1"
				(pin passive line
					(at 0 0 0)
					(length 0.635)
					(name "~"
						(effects
							(font
								(size 1.27 1.27)
							)
						)
					)
					(number "1"
						(effects
							(font
								(size 1.27 1.27)
							)
						)
					)
				)
				(pin passive line
					(at 5.08 0 180)
					(length 0.635)
					(name "~"
						(effects
							(font
								(size 1.27 1.27)
							)
						)
					)
					(number "2"
						(effects
							(font
								(size 1.27 1.27)
							)
						)
					)
				)
			)
		)
	(symbol "antmicroResistors0402:R_6k04_0.1%_0402"
			(pin_numbers
				(hide yes)
			)
			(pin_names
				(hide yes)
			)
			(exclude_from_sim no)
			(in_bom yes)
			(on_board yes)
			(property "Reference" "R"
				(at 20.32 -5.08 0)
				(effects
					(font
						(size 1.27 1.27)
						(thickness 0.15)
					)
					(justify left bottom)
				)
			)
			(property "Value" "R_6k04_0.1%_0402"
				(at 20.32 -12.7 0)
				(effects
					(font
						(size 1.27 1.27)
						(thickness 0.15)
					)
					(justify left bottom)
					(hide yes)
				)
			)
			(property "Footprint" "antmicro-footprints:R_0402_1005Metric"
				(at 20.32 -15.24 0)
				(effects
					(font
						(size 1.27 1.27)
						(thickness 0.15)
					)
					(justify left bottom)
					(hide yes)
				)
			)
			(property "Datasheet" "https://www.vishay.com/docs/28758/tnpw_e3.pdf"
				(at 20.32 -17.78 0)
				(effects
					(font
						(size 1.27 1.27)
						(thickness 0.15)
					)
					(justify left bottom)
					(hide yes)
				)
			)
			(property "Description" "SMD Chip Resistor, 6.49 kohm, ± 1%, 62.5 mW, 0402 [1005 Metric], Thick Film, General Purpose"
				(at 20.32 -30.48 0)
				(effects
					(font
						(size 1.27 1.27)
					)
					(justify left bottom)
					(hide yes)
				)
			)
			(property "MPN" "TNPW04026K04BEED"
				(at 20.32 -20.32 0)
				(effects
					(font
						(size 1.27 1.27)
						(thickness 0.15)
					)
					(justify left bottom)
					(hide yes)
				)
			)
			(property "Manufacturer" "Vishay"
				(at 20.32 -22.86 0)
				(effects
					(font
						(size 1.27 1.27)
						(thickness 0.15)
					)
					(justify left bottom)
					(hide yes)
				)
			)
			(property "License" "Apache-2.0"
				(at 20.32 -25.4 0)
				(effects
					(font
						(size 1.27 1.27)
						(thickness 0.15)
					)
					(justify left bottom)
					(hide yes)
				)
			)
			(property "Author" "Antmicro"
				(at 20.32 -27.94 0)
				(effects
					(font
						(size 1.27 1.27)
						(thickness 0.15)
					)
					(justify left bottom)
					(hide yes)
				)
			)
			(property "Val" "6k04"
				(at 20.32 -7.62 0)
				(effects
					(font
						(size 1.27 1.27)
						(thickness 0.15)
					)
					(justify left bottom)
				)
			)
			(property "Tolerance" "0.1%"
				(at 20.32 -10.16 0)
				(effects
					(font
						(size 1.27 1.27)
					)
					(justify left bottom)
				)
			)
			(property "ki_keywords" "0402, SMT, RESISTOR, PASSIVE"
				(at 0 0 0)
				(effects
					(font
						(size 1.27 1.27)
					)
					(hide yes)
				)
			)
			(symbol "R_6k04_0.1%_0402_0_1"
				(rectangle
					(start 0.635 0.889)
					(end 4.445 -0.889)
					(stroke
						(width 0.254)
						(type default)
					)
					(fill
						(type none)
					)
				)
			)
			(symbol "R_6k04_0.1%_0402_1_1"
				(pin passive line
					(at 0 0 0)
					(length 0.635)
					(name "~"
						(effects
							(font
								(size 1.27 1.27)
							)
						)
					)
					(number "1"
						(effects
							(font
								(size 1.27 1.27)
							)
						)
					)
				)
				(pin passive line
					(at 5.08 0 180)
					(length 0.635)
					(name "~"
						(effects
							(font
								(size 1.27 1.27)
							)
						)
					)
					(number "2"
						(effects
							(font
								(size 1.27 1.27)
							)
						)
					)
				)
			)
		)
	(symbol "antmicroResistors0402:R_8k2_0402"
			(pin_numbers
				(hide yes)
			)
			(pin_names
				(hide yes)
			)
			(exclude_from_sim no)
			(in_bom yes)
			(on_board yes)
			(property "Reference" "R"
				(at 20.32 -5.08 0)
				(effects
					(font
						(size 1.27 1.27)
						(thickness 0.15)
					)
					(justify left bottom)
				)
			)
			(property "Value" "R_8k2_0402"
				(at 20.32 -12.7 0)
				(effects
					(font
						(size 1.27 1.27)
						(thickness 0.15)
					)
					(justify left bottom)
					(hide yes)
				)
			)
			(property "Footprint" "antmicro-footprints:R_0402_1005Metric"
				(at 20.32 -15.24 0)
				(effects
					(font
						(size 1.27 1.27)
						(thickness 0.15)
					)
					(justify left bottom)
					(hide yes)
				)
			)
			(property "Datasheet" "https://www.bourns.com/docs/product-datasheets/cr.pdf"
				(at 20.32 -17.78 0)
				(effects
					(font
						(size 1.27 1.27)
						(thickness 0.15)
					)
					(justify left bottom)
					(hide yes)
				)
			)
			(property "Description" "SMD Chip Resistor"
				(at 20.32 -30.48 0)
				(effects
					(font
						(size 1.27 1.27)
					)
					(justify left bottom)
					(hide yes)
				)
			)
			(property "MPN" "CR0402-FX-8201GLF"
				(at 20.32 -20.32 0)
				(effects
					(font
						(size 1.27 1.27)
						(thickness 0.15)
					)
					(justify left bottom)
					(hide yes)
				)
			)
			(property "Manufacturer" "Bourns"
				(at 20.32 -22.86 0)
				(effects
					(font
						(size 1.27 1.27)
						(thickness 0.15)
					)
					(justify left bottom)
					(hide yes)
				)
			)
			(property "License" "Apache-2.0"
				(at 20.32 -25.4 0)
				(effects
					(font
						(size 1.27 1.27)
						(thickness 0.15)
					)
					(justify left bottom)
					(hide yes)
				)
			)
			(property "Author" "Antmicro"
				(at 20.32 -27.94 0)
				(effects
					(font
						(size 1.27 1.27)
						(thickness 0.15)
					)
					(justify left bottom)
					(hide yes)
				)
			)
			(property "Val" "8k2"
				(at 20.32 -7.62 0)
				(effects
					(font
						(size 1.27 1.27)
						(thickness 0.15)
					)
					(justify left bottom)
				)
			)
			(property "Tolerance" "1%"
				(at 20.32 -10.16 0)
				(effects
					(font
						(size 1.27 1.27)
					)
					(justify left bottom)
					(hide yes)
				)
			)
			(property "ki_keywords" "0402, SMT, RESISTOR, PASSIVE"
				(at 0 0 0)
				(effects
					(font
						(size 1.27 1.27)
					)
					(hide yes)
				)
			)
			(symbol "R_8k2_0402_0_1"
				(rectangle
					(start 0.635 0.889)
					(end 4.445 -0.889)
					(stroke
						(width 0.254)
						(type default)
					)
					(fill
						(type none)
					)
				)
			)
			(symbol "R_8k2_0402_1_1"
				(pin passive line
					(at 0 0 0)
					(length 0.635)
					(name "~"
						(effects
							(font
								(size 1.27 1.27)
							)
						)
					)
					(number "1"
						(effects
							(font
								(size 1.27 1.27)
							)
						)
					)
				)
				(pin passive line
					(at 5.08 0 180)
					(length 0.635)
					(name "~"
						(effects
							(font
								(size 1.27 1.27)
							)
						)
					)
					(number "2"
						(effects
							(font
								(size 1.27 1.27)
							)
						)
					)
				)
			)
		)
	(symbol "antmicroResistors0402:R_90k9_0402"
			(pin_numbers
				(hide yes)
			)
			(pin_names
				(hide yes)
			)
			(exclude_from_sim no)
			(in_bom yes)
			(on_board yes)
			(property "Reference" "R"
				(at 20.32 -5.08 0)
				(effects
					(font
						(size 1.27 1.27)
						(thickness 0.15)
					)
					(justify left bottom)
				)
			)
			(property "Value" "R_90k9_0402"
				(at 20.32 -12.7 0)
				(effects
					(font
						(size 1.27 1.27)
						(thickness 0.15)
					)
					(justify left bottom)
					(hide yes)
				)
			)
			(property "Footprint" "antmicro-footprints:R_0402_1005Metric"
				(at 20.32 -15.24 0)
				(effects
					(font
						(size 1.27 1.27)
						(thickness 0.15)
					)
					(justify left bottom)
					(hide yes)
				)
			)
			(property "Datasheet" "https://www.bourns.com/docs/product-datasheets/cr.pdf"
				(at 20.32 -17.78 0)
				(effects
					(font
						(size 1.27 1.27)
						(thickness 0.15)
					)
					(justify left bottom)
					(hide yes)
				)
			)
			(property "Description" "SMD Chip Resistor"
				(at 20.32 -30.48 0)
				(effects
					(font
						(size 1.27 1.27)
					)
					(justify left bottom)
					(hide yes)
				)
			)
			(property "MPN" "CR0402-FX-9092GLF"
				(at 20.32 -20.32 0)
				(effects
					(font
						(size 1.27 1.27)
						(thickness 0.15)
					)
					(justify left bottom)
					(hide yes)
				)
			)
			(property "Manufacturer" "Bourns"
				(at 20.32 -22.86 0)
				(effects
					(font
						(size 1.27 1.27)
						(thickness 0.15)
					)
					(justify left bottom)
					(hide yes)
				)
			)
			(property "License" "Apache-2.0"
				(at 20.32 -25.4 0)
				(effects
					(font
						(size 1.27 1.27)
						(thickness 0.15)
					)
					(justify left bottom)
					(hide yes)
				)
			)
			(property "Author" "Antmicro"
				(at 20.32 -27.94 0)
				(effects
					(font
						(size 1.27 1.27)
						(thickness 0.15)
					)
					(justify left bottom)
					(hide yes)
				)
			)
			(property "Val" "90k9"
				(at 20.32 -7.62 0)
				(effects
					(font
						(size 1.27 1.27)
						(thickness 0.15)
					)
					(justify left bottom)
				)
			)
			(property "Tolerance" "1%"
				(at 20.32 -10.16 0)
				(effects
					(font
						(size 1.27 1.27)
					)
					(justify left bottom)
					(hide yes)
				)
			)
			(property "ki_keywords" "0402, SMT, RESISTOR, PASSIVE"
				(at 0 0 0)
				(effects
					(font
						(size 1.27 1.27)
					)
					(hide yes)
				)
			)
			(symbol "R_90k9_0402_0_1"
				(rectangle
					(start 0.635 0.889)
					(end 4.445 -0.889)
					(stroke
						(width 0.254)
						(type default)
					)
					(fill
						(type none)
					)
				)
			)
			(symbol "R_90k9_0402_1_1"
				(pin passive line
					(at 0 0 0)
					(length 0.635)
					(name "~"
						(effects
							(font
								(size 1.27 1.27)
							)
						)
					)
					(number "1"
						(effects
							(font
								(size 1.27 1.27)
							)
						)
					)
				)
				(pin passive line
					(at 5.08 0 180)
					(length 0.635)
					(name "~"
						(effects
							(font
								(size 1.27 1.27)
							)
						)
					)
					(number "2"
						(effects
							(font
								(size 1.27 1.27)
							)
						)
					)
				)
			)
		)
	(symbol "antmicroResistors0603:R_0R_22.4A_0603"
			(pin_numbers
				(hide yes)
			)
			(pin_names
				(hide yes)
			)
			(exclude_from_sim no)
			(in_bom yes)
			(on_board yes)
			(property "Reference" "R"
				(at 15.24 -2.54 0)
				(effects
					(font
						(size 1.27 1.27)
						(thickness 0.15)
					)
					(justify left bottom)
				)
			)
			(property "Value" "R_0R_22.4A_0603"
				(at 15.24 -5.08 0)
				(effects
					(font
						(size 1.27 1.27)
						(thickness 0.15)
					)
					(justify left bottom)
					(hide yes)
				)
			)
			(property "Footprint" "antmicro-footprints:R_0603_1608Metric"
				(at 15.24 -10.16 0)
				(effects
					(font
						(size 1.27 1.27)
						(thickness 0.15)
					)
					(justify left bottom)
					(hide yes)
				)
			)
			(property "Datasheet" "https://fscdn.rohm.com/en/products/databook/datasheet/passive/resistor/chip_resistor/pmr-jpw-e.pdf"
				(at 15.24 -12.7 0)
				(effects
					(font
						(size 1.27 1.27)
						(thickness 0.15)
					)
					(justify left bottom)
					(hide yes)
				)
			)
			(property "Description" "SMD Chip Resistor"
				(at 15.24 -27.94 0)
				(effects
					(font
						(size 1.27 1.27)
					)
					(justify left bottom)
					(hide yes)
				)
			)
			(property "MPN" "PMR03EZPJ000"
				(at 15.24 -15.24 0)
				(effects
					(font
						(size 1.27 1.27)
						(thickness 0.15)
					)
					(justify left bottom)
					(hide yes)
				)
			)
			(property "Manufacturer" "ROHM Semiconductor"
				(at 15.24 -17.78 0)
				(effects
					(font
						(size 1.27 1.27)
						(thickness 0.15)
					)
					(justify left bottom)
					(hide yes)
				)
			)
			(property "Val" "0R"
				(at 15.24 -7.62 0)
				(effects
					(font
						(size 1.27 1.27)
						(thickness 0.15)
					)
					(justify left bottom)
				)
			)
			(property "Max. Curr." "22.4A"
				(at 15.24 -20.32 0)
				(effects
					(font
						(size 1.27 1.27)
						(thickness 0.15)
					)
					(justify left bottom)
				)
			)
			(property "Author" "Antmicro"
				(at 15.24 -22.86 0)
				(effects
					(font
						(size 1.27 1.27)
						(thickness 0.15)
					)
					(justify left bottom)
					(hide yes)
				)
			)
			(property "License" "Apache-2.0"
				(at 15.24 -25.4 0)
				(effects
					(font
						(size 1.27 1.27)
						(thickness 0.15)
					)
					(justify left bottom)
					(hide yes)
				)
			)
			(property "Tolerance" "template_tolerance"
				(at 20.32 -10.16 0)
				(effects
					(font
						(size 1.27 1.27)
					)
					(justify left bottom)
					(hide yes)
				)
			)
			(property "ki_keywords" "0603, SMT, RESISTOR, PASSIVE"
				(at 0 0 0)
				(effects
					(font
						(size 1.27 1.27)
					)
					(hide yes)
				)
			)
			(symbol "R_0R_22.4A_0603_0_1"
				(rectangle
					(start 0.635 0.889)
					(end 4.445 -0.889)
					(stroke
						(width 0.254)
						(type default)
					)
					(fill
						(type none)
					)
				)
			)
			(symbol "R_0R_22.4A_0603_1_1"
				(pin passive line
					(at 0 0 0)
					(length 0.635)
					(name "~"
						(effects
							(font
								(size 1.27 1.27)
							)
						)
					)
					(number "1"
						(effects
							(font
								(size 1.27 1.27)
							)
						)
					)
				)
				(pin passive line
					(at 5.08 0 180)
					(length 0.635)
					(name "~"
						(effects
							(font
								(size 1.27 1.27)
							)
						)
					)
					(number "2"
						(effects
							(font
								(size 1.27 1.27)
							)
						)
					)
				)
			)
		)
	(symbol "antmicroResonators:Resonator_50MHz_XRCGE"
			(pin_names
				(hide yes)
			)
			(exclude_from_sim no)
			(in_bom yes)
			(on_board yes)
			(property "Reference" "Y"
				(at 22.86 -2.54 0)
				(effects
					(font
						(size 1.27 1.27)
						(thickness 0.15)
					)
					(justify left bottom)
				)
			)
			(property "Value" "Resonator_50MHz_XRCGE"
				(at 22.86 -7.62 0)
				(effects
					(font
						(size 1.27 1.27)
						(thickness 0.15)
					)
					(justify left bottom)
					(hide yes)
				)
			)
			(property "Footprint" "antmicro-footprints:Resonator_SMD_Murata_XRCGB_2x1.6x0.65mm"
				(at 22.86 -10.16 0)
				(effects
					(font
						(size 1.27 1.27)
						(thickness 0.15)
					)
					(justify left bottom)
					(hide yes)
				)
			)
			(property "Datasheet" "https://www.murata.com/products/productdata/8813268205598/SPEC-XRCGE50M000F5A2AR0.pdf"
				(at 22.86 -12.7 0)
				(effects
					(font
						(size 1.27 1.27)
						(thickness 0.15)
					)
					(justify left bottom)
					(hide yes)
				)
			)
			(property "Description" "Crystal, 50 MHz, 2mm x 1.6mm, 50 ppm, 4.7 pF, 50 ppm, XRCGE Series"
				(at 22.86 -27.94 0)
				(effects
					(font
						(size 1.27 1.27)
					)
					(justify left bottom)
					(hide yes)
				)
			)
			(property "Manufacturer" "Murata"
				(at 22.86 -25.4 0)
				(effects
					(font
						(size 1.27 1.27)
					)
					(justify left bottom)
					(hide yes)
				)
			)
			(property "MPN" "XRCGE50M000F5A2AR0"
				(at 22.86 -22.86 0)
				(effects
					(font
						(size 1.27 1.27)
					)
					(justify left bottom)
				)
			)
			(property "Val" "50MHz"
				(at 22.86 -5.08 0)
				(effects
					(font
						(size 1.27 1.27)
					)
					(justify left bottom)
				)
			)
			(property "CLoad" "4.7pF"
				(at 22.86 -20.32 0)
				(effects
					(font
						(size 1.27 1.27)
					)
					(justify left bottom)
					(hide yes)
				)
			)
			(property "Author" "Antmicro"
				(at 22.86 -15.24 0)
				(effects
					(font
						(size 1.27 1.27)
					)
					(justify left bottom)
					(hide yes)
				)
			)
			(property "License" "Apache-2.0"
				(at 22.86 -17.78 0)
				(effects
					(font
						(size 1.27 1.27)
					)
					(justify left bottom)
					(hide yes)
				)
			)
			(property "ki_keywords" "OSCILLATOR"
				(at 0 0 0)
				(effects
					(font
						(size 1.27 1.27)
					)
					(hide yes)
				)
			)
			(symbol "Resonator_50MHz_XRCGE_1_1"
				(polyline
					(pts
						(xy 1.905 1.905) (xy 1.905 2.54) (xy 5.715 2.54) (xy 5.715 1.905)
					)
					(stroke
						(width 0.254)
						(type default)
					)
					(fill
						(type none)
					)
				)
				(polyline
					(pts
						(xy 1.905 -1.905) (xy 1.905 -2.54) (xy 5.715 -2.54) (xy 5.715 -1.905)
					)
					(stroke
						(width 0.254)
						(type default)
					)
					(fill
						(type none)
					)
				)
				(polyline
					(pts
						(xy 2.54 1.27) (xy 2.54 -1.27)
					)
					(stroke
						(width 0.254)
						(type default)
					)
					(fill
						(type background)
					)
				)
				(rectangle
					(start 3.175 1.905)
					(end 4.445 -1.905)
					(stroke
						(width 0.254)
						(type default)
					)
					(fill
						(type background)
					)
				)
				(polyline
					(pts
						(xy 5.08 1.27) (xy 5.08 -1.27)
					)
					(stroke
						(width 0.254)
						(type default)
					)
					(fill
						(type background)
					)
				)
				(pin passive line
					(at 0 0 0)
					(length 2.54)
					(name "~"
						(effects
							(font
								(size 1.27 1.27)
							)
						)
					)
					(number "1"
						(effects
							(font
								(size 1.27 1.27)
							)
						)
					)
				)
				(pin passive line
					(at 3.81 -5.08 90)
					(length 2.54)
					(name "SH"
						(effects
							(font
								(size 1.27 1.27)
							)
						)
					)
					(number "2"
						(effects
							(font
								(size 1.27 1.27)
							)
						)
					)
				)
				(pin passive line
					(at 3.81 -5.08 90)
					(length 2.54)
					(hide yes)
					(name "SH"
						(effects
							(font
								(size 1.27 1.27)
							)
						)
					)
					(number "4"
						(effects
							(font
								(size 1.27 1.27)
							)
						)
					)
				)
				(pin passive line
					(at 7.62 0 180)
					(length 2.54)
					(name "~"
						(effects
							(font
								(size 1.27 1.27)
							)
						)
					)
					(number "3"
						(effects
							(font
								(size 1.27 1.27)
							)
						)
					)
				)
			)
		)
	(symbol "antmicroSlideSwitches:SW_DS04-254-1-01BK-SMT"
			(exclude_from_sim no)
			(in_bom yes)
			(on_board yes)
			(property "Reference" "SW"
				(at 26.67 -2.54 0)
				(effects
					(font
						(size 1.27 1.27)
						(thickness 0.15)
					)
					(justify left bottom)
				)
			)
			(property "Value" "SW_DS04-254-1-01BK-SMT"
				(at 26.67 -5.08 0)
				(effects
					(font
						(size 1.27 1.27)
						(thickness 0.15)
					)
					(justify left bottom)
					(hide yes)
				)
			)
			(property "Footprint" "antmicro-footprints:SW_DS04-254-1-01BK-SMT"
				(at 26.67 -7.62 0)
				(effects
					(font
						(size 1.27 1.27)
						(thickness 0.15)
					)
					(justify left bottom)
					(hide yes)
				)
			)
			(property "Datasheet" "https://www.mouser.com/datasheet/2/670/ds04_254_smt-1777718.pdf"
				(at 26.67 -10.16 0)
				(effects
					(font
						(size 1.27 1.27)
						(thickness 0.15)
					)
					(justify left bottom)
					(hide yes)
				)
			)
			(property "Description" "Slide switch"
				(at 26.67 -22.86 0)
				(effects
					(font
						(size 1.27 1.27)
					)
					(justify left bottom)
					(hide yes)
				)
			)
			(property "MPN" "DS04-254-1-01BK-SMT"
				(at 26.67 -12.7 0)
				(effects
					(font
						(size 1.27 1.27)
						(thickness 0.15)
					)
					(justify left bottom)
				)
			)
			(property "Manufacturer" "CUI Inc"
				(at 26.67 -15.24 0)
				(effects
					(font
						(size 1.27 1.27)
						(thickness 0.15)
					)
					(justify left bottom)
					(hide yes)
				)
			)
			(property "Author" "Antmicro"
				(at 26.67 -17.78 0)
				(effects
					(font
						(size 1.27 1.27)
						(thickness 0.15)
					)
					(justify left bottom)
					(hide yes)
				)
			)
			(property "License" "Apache-2.0"
				(at 26.67 -20.32 0)
				(effects
					(font
						(size 1.27 1.27)
						(thickness 0.15)
					)
					(justify left bottom)
					(hide yes)
				)
			)
			(property "ki_keywords" "HORIZONTAL, SMT, SWITCH, MECHANICAL, SLIDE"
				(at 0 0 0)
				(effects
					(font
						(size 1.27 1.27)
					)
					(hide yes)
				)
			)
			(property "ki_fp_filters" "SW?DIP?x1*"
				(at 0 0 0)
				(effects
					(font
						(size 1.27 1.27)
					)
					(hide yes)
				)
			)
			(symbol "SW_DS04-254-1-01BK-SMT_0_1"
				(polyline
					(pts
						(xy 3.81 0) (xy 2.54 0)
					)
					(stroke
						(width 0.254)
						(type default)
					)
					(fill
						(type none)
					)
				)
				(polyline
					(pts
						(xy 10.16 0) (xy 8.89 0)
					)
					(stroke
						(width 0.254)
						(type default)
					)
					(fill
						(type none)
					)
				)
			)
			(symbol "SW_DS04-254-1-01BK-SMT_1_1"
				(rectangle
					(start 2.54 2.54)
					(end 10.16 -2.54)
					(stroke
						(width 0.254)
						(type default)
					)
					(fill
						(type background)
					)
				)
				(circle
					(center 4.318 0)
					(radius 0.508)
					(stroke
						(width 0.254)
						(type default)
					)
					(fill
						(type background)
					)
				)
				(polyline
					(pts
						(xy 4.826 0.127) (xy 8.7122 1.1684)
					)
					(stroke
						(width 0.254)
						(type default)
					)
					(fill
						(type background)
					)
				)
				(circle
					(center 8.382 0)
					(radius 0.508)
					(stroke
						(width 0.254)
						(type default)
					)
					(fill
						(type background)
					)
				)
				(pin passive line
					(at 0 0 0)
					(length 2.54)
					(name "~"
						(effects
							(font
								(size 1.27 1.27)
							)
						)
					)
					(number "1"
						(effects
							(font
								(size 1.27 1.27)
							)
						)
					)
				)
				(pin passive line
					(at 12.7 0 180)
					(length 2.54)
					(name "~"
						(effects
							(font
								(size 1.27 1.27)
							)
						)
					)
					(number "2"
						(effects
							(font
								(size 1.27 1.27)
							)
						)
					)
				)
			)
		)
	(symbol "antmicroTVSDiodes:ESD204DQAR"
			(exclude_from_sim no)
			(in_bom yes)
			(on_board yes)
			(property "Reference" "D"
				(at 24.13 0 0)
				(effects
					(font
						(size 1.27 1.27)
						(thickness 0.15)
					)
					(justify left bottom)
				)
			)
			(property "Value" "ESD204DQAR"
				(at 24.13 -5.08 0)
				(effects
					(font
						(size 1.27 1.27)
						(thickness 0.15)
					)
					(justify left bottom)
					(hide yes)
				)
			)
			(property "Footprint" "antmicro-footprints:USON-10_2.5x1mm_P0.5mm"
				(at 24.13 -7.62 0)
				(effects
					(font
						(size 1.27 1.27)
						(thickness 0.15)
					)
					(justify left bottom)
					(hide yes)
				)
			)
			(property "Datasheet" "https://www.ti.com/lit/ds/symlink/esd204.pdf?ts=1706004844383&ref_url=https%253A%252F%252Fwww.ti.com%252Finterface%252Fdiodes%252Fesd-protection-diodes%252Fproducts.html"
				(at 24.13 -10.16 0)
				(effects
					(font
						(size 1.27 1.27)
						(thickness 0.15)
					)
					(justify left bottom)
					(hide yes)
				)
			)
			(property "Description" "TVS diode array, 30 kV, USON-10, 3.6 V, 0.55 pF"
				(at 24.13 -20.32 0)
				(effects
					(font
						(size 1.27 1.27)
					)
					(justify left bottom)
					(hide yes)
				)
			)
			(property "MPN" "ESD204DQAR"
				(at 24.13 -2.54 0)
				(effects
					(font
						(size 1.27 1.27)
						(thickness 0.15)
					)
					(justify left bottom)
				)
			)
			(property "Manufacturer" "Texas Instruments"
				(at 24.13 -12.7 0)
				(effects
					(font
						(size 1.27 1.27)
						(thickness 0.15)
					)
					(justify left bottom)
					(hide yes)
				)
			)
			(property "Author" "Antmicro"
				(at 24.13 -15.24 0)
				(effects
					(font
						(size 1.27 1.27)
						(thickness 0.15)
					)
					(justify left bottom)
					(hide yes)
				)
			)
			(property "License" "Apache-2.0"
				(at 24.13 -17.78 0)
				(effects
					(font
						(size 1.27 1.27)
						(thickness 0.15)
					)
					(justify left bottom)
					(hide yes)
				)
			)
			(property "ki_keywords" "SMT, DIODE, SEMICONDUCTOR, TVS, ESD"
				(at 0 0 0)
				(effects
					(font
						(size 1.27 1.27)
					)
					(hide yes)
				)
			)
			(symbol "ESD204DQAR_1_1"
				(rectangle
					(start 2.54 2.54)
					(end 8.89 -12.7)
					(stroke
						(width 0.254)
						(type default)
					)
					(fill
						(type background)
					)
				)
				(polyline
					(pts
						(xy 2.54 0) (xy 7.62 0)
					)
					(stroke
						(width 0.254)
						(type default)
					)
					(fill
						(type background)
					)
				)
				(polyline
					(pts
						(xy 2.54 -2.54) (xy 7.62 -2.54)
					)
					(stroke
						(width 0.254)
						(type default)
					)
					(fill
						(type background)
					)
				)
				(polyline
					(pts
						(xy 2.54 -5.08) (xy 7.62 -5.08)
					)
					(stroke
						(width 0.254)
						(type default)
					)
					(fill
						(type background)
					)
				)
				(polyline
					(pts
						(xy 2.54 -7.62) (xy 7.62 -7.62)
					)
					(stroke
						(width 0.254)
						(type default)
					)
					(fill
						(type background)
					)
				)
				(polyline
					(pts
						(xy 4.826 -0.635) (xy 5.08 -0.381) (xy 5.08 0.381) (xy 5.334 0.635)
					)
					(stroke
						(width 0.254)
						(type default)
					)
					(fill
						(type background)
					)
				)
				(polyline
					(pts
						(xy 4.826 -3.175) (xy 5.08 -2.921) (xy 5.08 -2.159) (xy 5.334 -1.905)
					)
					(stroke
						(width 0.254)
						(type default)
					)
					(fill
						(type background)
					)
				)
				(polyline
					(pts
						(xy 4.826 -5.715) (xy 5.08 -5.461) (xy 5.08 -4.699) (xy 5.334 -4.445)
					)
					(stroke
						(width 0.254)
						(type default)
					)
					(fill
						(type background)
					)
				)
				(polyline
					(pts
						(xy 4.826 -8.255) (xy 5.08 -8.001) (xy 5.08 -7.239) (xy 5.334 -6.985)
					)
					(stroke
						(width 0.254)
						(type default)
					)
					(fill
						(type background)
					)
				)
				(polyline
					(pts
						(xy 5.08 0) (xy 3.81 -0.635) (xy 3.81 0.635) (xy 5.08 0)
					)
					(stroke
						(width 0.254)
						(type default)
					)
					(fill
						(type background)
					)
				)
				(polyline
					(pts
						(xy 5.08 0) (xy 6.35 -0.635) (xy 6.35 0.635) (xy 5.08 0)
					)
					(stroke
						(width 0.254)
						(type default)
					)
					(fill
						(type background)
					)
				)
				(polyline
					(pts
						(xy 5.08 -2.54) (xy 3.81 -3.175) (xy 3.81 -1.905) (xy 5.08 -2.54)
					)
					(stroke
						(width 0.254)
						(type default)
					)
					(fill
						(type background)
					)
				)
				(polyline
					(pts
						(xy 5.08 -2.54) (xy 6.35 -3.175) (xy 6.35 -1.905) (xy 5.08 -2.54)
					)
					(stroke
						(width 0.254)
						(type default)
					)
					(fill
						(type background)
					)
				)
				(polyline
					(pts
						(xy 5.08 -5.08) (xy 3.81 -5.715) (xy 3.81 -4.445) (xy 5.08 -5.08)
					)
					(stroke
						(width 0.254)
						(type default)
					)
					(fill
						(type background)
					)
				)
				(polyline
					(pts
						(xy 5.08 -5.08) (xy 6.35 -4.445) (xy 6.35 -5.715) (xy 5.08 -5.08)
					)
					(stroke
						(width 0.254)
						(type default)
					)
					(fill
						(type background)
					)
				)
				(polyline
					(pts
						(xy 5.08 -7.62) (xy 3.81 -8.255) (xy 3.81 -6.985) (xy 5.08 -7.62)
					)
					(stroke
						(width 0.254)
						(type default)
					)
					(fill
						(type background)
					)
				)
				(polyline
					(pts
						(xy 6.35 -6.985) (xy 6.35 -8.255) (xy 5.08 -7.62) (xy 6.35 -6.985)
					)
					(stroke
						(width 0.254)
						(type default)
					)
					(fill
						(type background)
					)
				)
				(polyline
					(pts
						(xy 7.62 0) (xy 7.62 -10.16)
					)
					(stroke
						(width 0.254)
						(type default)
					)
					(fill
						(type background)
					)
				)
				(circle
					(center 7.62 -2.54)
					(radius 0.254)
					(stroke
						(width 0.254)
						(type default)
					)
					(fill
						(type background)
					)
				)
				(circle
					(center 7.62 -5.08)
					(radius 0.254)
					(stroke
						(width 0.254)
						(type default)
					)
					(fill
						(type background)
					)
				)
				(circle
					(center 7.62 -5.08)
					(radius 0.254)
					(stroke
						(width 0.254)
						(type default)
					)
					(fill
						(type background)
					)
				)
				(circle
					(center 7.62 -7.62)
					(radius 0.254)
					(stroke
						(width 0.254)
						(type default)
					)
					(fill
						(type background)
					)
				)
				(polyline
					(pts
						(xy 7.62 -10.16) (xy 2.54 -10.16)
					)
					(stroke
						(width 0.254)
						(type default)
					)
					(fill
						(type background)
					)
				)
				(pin passive line
					(at 0 0 0)
					(length 2.54)
					(name "~"
						(effects
							(font
								(size 1.27 1.27)
							)
						)
					)
					(number "1"
						(effects
							(font
								(size 1.27 1.27)
							)
						)
					)
				)
				(pin passive line
					(at 0 0 0)
					(length 2.54)
					(hide yes)
					(name "~"
						(effects
							(font
								(size 1.27 1.27)
							)
						)
					)
					(number "10"
						(effects
							(font
								(size 1.27 1.27)
							)
						)
					)
				)
				(pin passive line
					(at 0 -2.54 0)
					(length 2.54)
					(name "~"
						(effects
							(font
								(size 1.27 1.27)
							)
						)
					)
					(number "2"
						(effects
							(font
								(size 1.27 1.27)
							)
						)
					)
				)
				(pin passive line
					(at 0 -2.54 0)
					(length 2.54)
					(hide yes)
					(name "~"
						(effects
							(font
								(size 1.27 1.27)
							)
						)
					)
					(number "9"
						(effects
							(font
								(size 1.27 1.27)
							)
						)
					)
				)
				(pin passive line
					(at 0 -5.08 0)
					(length 2.54)
					(name "~"
						(effects
							(font
								(size 1.27 1.27)
							)
						)
					)
					(number "4"
						(effects
							(font
								(size 1.27 1.27)
							)
						)
					)
				)
				(pin passive line
					(at 0 -5.08 0)
					(length 2.54)
					(hide yes)
					(name "~"
						(effects
							(font
								(size 1.27 1.27)
							)
						)
					)
					(number "7"
						(effects
							(font
								(size 1.27 1.27)
							)
						)
					)
				)
				(pin passive line
					(at 0 -7.62 0)
					(length 2.54)
					(name "~"
						(effects
							(font
								(size 1.27 1.27)
							)
						)
					)
					(number "5"
						(effects
							(font
								(size 1.27 1.27)
							)
						)
					)
				)
				(pin passive line
					(at 0 -7.62 0)
					(length 2.54)
					(hide yes)
					(name "~"
						(effects
							(font
								(size 1.27 1.27)
							)
						)
					)
					(number "6"
						(effects
							(font
								(size 1.27 1.27)
							)
						)
					)
				)
				(pin power_in line
					(at 0 -10.16 0)
					(length 2.54)
					(name "~"
						(effects
							(font
								(size 1.27 1.27)
							)
						)
					)
					(number "3"
						(effects
							(font
								(size 1.27 1.27)
							)
						)
					)
				)
				(pin passive line
					(at 0 -10.16 0)
					(length 2.54)
					(hide yes)
					(name "~"
						(effects
							(font
								(size 1.27 1.27)
							)
						)
					)
					(number "8"
						(effects
							(font
								(size 1.27 1.27)
							)
						)
					)
				)
			)
		)
	(symbol "antmicroTVSDiodes:PESD5Z5_0F"
			(pin_numbers
				(hide yes)
			)
			(pin_names
				(hide yes)
			)
			(exclude_from_sim no)
			(in_bom yes)
			(on_board yes)
			(property "Reference" "D"
				(at 15.24 0 0)
				(effects
					(font
						(size 1.27 1.27)
						(thickness 0.15)
					)
					(justify left bottom)
				)
			)
			(property "Value" "PESD5Z5_0F"
				(at 15.24 -12.7 0)
				(effects
					(font
						(size 1.27 1.27)
						(thickness 0.15)
					)
					(justify left bottom)
					(hide yes)
				)
			)
			(property "Footprint" "antmicro-footprints:SOD-523"
				(at 15.24 -5.08 0)
				(effects
					(font
						(size 1.27 1.27)
						(thickness 0.15)
					)
					(justify left bottom)
					(hide yes)
				)
			)
			(property "Datasheet" "https://assets.nexperia.com/documents/data-sheet/PESD5Z5_0.pdf"
				(at 15.24 -7.62 0)
				(effects
					(font
						(size 1.27 1.27)
						(thickness 0.15)
					)
					(justify left bottom)
					(hide yes)
				)
			)
			(property "Description" "Unidirectional TVS, 30 kV,  SOD-523, 5 V, 89 pF"
				(at 15.24 -20.32 0)
				(effects
					(font
						(size 1.27 1.27)
					)
					(justify left bottom)
					(hide yes)
				)
			)
			(property "Manufacturer" "Nexperia"
				(at 15.24 -10.16 0)
				(effects
					(font
						(size 1.27 1.27)
						(thickness 0.15)
					)
					(justify left bottom)
					(hide yes)
				)
			)
			(property "MPN" "PESD5Z5.0F"
				(at 15.24 -2.54 0)
				(effects
					(font
						(size 1.27 1.27)
						(thickness 0.15)
					)
					(justify left bottom)
				)
			)
			(property "Author" "Antmicro"
				(at 15.24 -15.24 0)
				(effects
					(font
						(size 1.27 1.27)
						(thickness 0.15)
					)
					(justify left bottom)
					(hide yes)
				)
			)
			(property "License" "Apache-2.0"
				(at 15.24 -17.78 0)
				(effects
					(font
						(size 1.27 1.27)
						(thickness 0.15)
					)
					(justify left bottom)
					(hide yes)
				)
			)
			(property "ki_keywords" "DIODE, SEMICONDUCTOR, TVS, ESD"
				(at 0 0 0)
				(effects
					(font
						(size 1.27 1.27)
					)
					(hide yes)
				)
			)
			(symbol "PESD5Z5_0F_0_1"
				(polyline
					(pts
						(xy 1.905 0) (xy 0.635 0)
					)
					(stroke
						(width 0)
						(type default)
					)
					(fill
						(type none)
					)
				)
				(polyline
					(pts
						(xy 4.445 0) (xy 3.175 0)
					)
					(stroke
						(width 0)
						(type default)
					)
					(fill
						(type none)
					)
				)
			)
			(symbol "PESD5Z5_0F_1_1"
				(polyline
					(pts
						(xy 1.778 1.016) (xy 1.397 1.016)
					)
					(stroke
						(width 0.254)
						(type default)
					)
					(fill
						(type none)
					)
				)
				(polyline
					(pts
						(xy 1.778 1.016) (xy 1.778 -1.016)
					)
					(stroke
						(width 0.254)
						(type default)
					)
					(fill
						(type none)
					)
				)
				(polyline
					(pts
						(xy 2.159 -1.016) (xy 1.778 -1.016)
					)
					(stroke
						(width 0.254)
						(type default)
					)
					(fill
						(type none)
					)
				)
				(polyline
					(pts
						(xy 3.302 1.016) (xy 3.302 -1.016) (xy 1.778 0) (xy 3.302 1.016)
					)
					(stroke
						(width 0.254)
						(type default)
					)
					(fill
						(type outline)
					)
				)
				(pin passive line
					(at 0 0 0)
					(length 0.635)
					(name "C"
						(effects
							(font
								(size 1.27 1.27)
							)
						)
					)
					(number "1"
						(effects
							(font
								(size 1.27 1.27)
							)
						)
					)
				)
				(pin passive line
					(at 5.08 0 180)
					(length 0.635)
					(name "A"
						(effects
							(font
								(size 1.27 1.27)
							)
						)
					)
					(number "2"
						(effects
							(font
								(size 1.27 1.27)
							)
						)
					)
				)
			)
		)
	(symbol "antmicroTVSDiodes:SZSMF4L14AT3G"
			(pin_numbers
				(hide yes)
			)
			(pin_names
				(hide yes)
			)
			(exclude_from_sim no)
			(in_bom yes)
			(on_board yes)
			(property "Reference" "D"
				(at 15.24 -5.08 0)
				(effects
					(font
						(size 1.27 1.27)
						(thickness 0.15)
					)
					(justify left bottom)
				)
			)
			(property "Value" "SZSMF4L14AT3G"
				(at 15.24 -10.16 0)
				(effects
					(font
						(size 1.27 1.27)
						(thickness 0.15)
					)
					(justify left bottom)
					(hide yes)
				)
			)
			(property "Footprint" "antmicro-footprints:SOD-123FL"
				(at 15.24 -12.7 0)
				(effects
					(font
						(size 1.27 1.27)
						(thickness 0.15)
					)
					(justify left bottom)
					(hide yes)
				)
			)
			(property "Datasheet" "https://www.mouser.com/datasheet/2/240/media-3320461.pdf"
				(at 15.24 -15.24 0)
				(effects
					(font
						(size 1.27 1.27)
						(thickness 0.15)
					)
					(justify left bottom)
					(hide yes)
				)
			)
			(property "Description" "ESD, TVS Diode, 14V, UNI, 400W, SOD-123FL"
				(at 15.24 -25.4 0)
				(effects
					(font
						(size 1.27 1.27)
					)
					(justify left bottom)
					(hide yes)
				)
			)
			(property "MPN" "SZSMF4L12AT3G"
				(at 15.24 -7.62 0)
				(effects
					(font
						(size 1.27 1.27)
						(thickness 0.15)
					)
					(justify left bottom)
				)
			)
			(property "Author" "Antmicro"
				(at 15.24 -17.78 0)
				(effects
					(font
						(size 1.27 1.27)
						(thickness 0.15)
					)
					(justify left bottom)
					(hide yes)
				)
			)
			(property "License" "Apache-2.0"
				(at 15.24 -20.32 0)
				(effects
					(font
						(size 1.27 1.27)
						(thickness 0.15)
					)
					(justify left bottom)
					(hide yes)
				)
			)
			(property "Manufacturer" "Littelfuse"
				(at 15.24 -22.86 0)
				(effects
					(font
						(size 1.27 1.27)
						(thickness 0.15)
					)
					(justify left bottom)
					(hide yes)
				)
			)
			(property "ki_keywords" "SMT, DIODE, SEMICONDUCTOR, ESD, TVS"
				(at 0 0 0)
				(effects
					(font
						(size 1.27 1.27)
					)
					(hide yes)
				)
			)
			(symbol "SZSMF4L14AT3G_0_1"
				(polyline
					(pts
						(xy 1.905 0) (xy 0.635 0)
					)
					(stroke
						(width 0)
						(type default)
					)
					(fill
						(type none)
					)
				)
				(polyline
					(pts
						(xy 4.445 0) (xy 3.175 0)
					)
					(stroke
						(width 0)
						(type default)
					)
					(fill
						(type none)
					)
				)
			)
			(symbol "SZSMF4L14AT3G_1_1"
				(polyline
					(pts
						(xy 1.778 1.016) (xy 1.397 1.016)
					)
					(stroke
						(width 0.254)
						(type default)
					)
					(fill
						(type none)
					)
				)
				(polyline
					(pts
						(xy 1.778 1.016) (xy 1.778 -1.016)
					)
					(stroke
						(width 0.254)
						(type default)
					)
					(fill
						(type none)
					)
				)
				(polyline
					(pts
						(xy 2.159 -1.016) (xy 1.778 -1.016)
					)
					(stroke
						(width 0.254)
						(type default)
					)
					(fill
						(type none)
					)
				)
				(polyline
					(pts
						(xy 3.302 1.016) (xy 3.302 -1.016) (xy 1.778 0) (xy 3.302 1.016)
					)
					(stroke
						(width 0.254)
						(type default)
					)
					(fill
						(type outline)
					)
				)
				(pin passive line
					(at 0 0 0)
					(length 0.635)
					(name "C"
						(effects
							(font
								(size 1.27 1.27)
							)
						)
					)
					(number "1"
						(effects
							(font
								(size 1.27 1.27)
							)
						)
					)
				)
				(pin passive line
					(at 5.08 0 180)
					(length 0.635)
					(name "A"
						(effects
							(font
								(size 1.27 1.27)
							)
						)
					)
					(number "2"
						(effects
							(font
								(size 1.27 1.27)
							)
						)
					)
				)
			)
		)
	(symbol "antmicroTemperatureSensorsAnalogandDigitalOutput:MAX31740ATA+T"
			(exclude_from_sim no)
			(in_bom yes)
			(on_board yes)
			(property "Reference" "U"
				(at 35.56 -2.54 0)
				(effects
					(font
						(size 1.27 1.27)
						(thickness 0.15)
					)
					(justify left bottom)
				)
			)
			(property "Value" "MAX31740ATA+T"
				(at 35.56 -7.62 0)
				(effects
					(font
						(size 1.27 1.27)
						(thickness 0.15)
					)
					(justify left bottom)
					(hide yes)
				)
			)
			(property "Footprint" "antmicro-footprints:TDFN-8-1EP_2x3x0.75mm_P0.5mm_EP1.75x1.63mm"
				(at 35.56 -10.16 0)
				(effects
					(font
						(size 1.27 1.27)
						(thickness 0.15)
					)
					(justify left bottom)
					(hide yes)
				)
			)
			(property "Datasheet" "https://www.analog.com/media/en/technical-documentation/data-sheets/max31740.pdf"
				(at 35.56 -12.7 0)
				(effects
					(font
						(size 1.27 1.27)
						(thickness 0.15)
					)
					(justify left bottom)
					(hide yes)
				)
			)
			(property "Description" "Pwm fan speed controller, temperature measurement, Control speed of 2-, 3-, 4- Wire Fans"
				(at 35.56 -22.86 0)
				(effects
					(font
						(size 1.27 1.27)
					)
					(justify left bottom)
					(hide yes)
				)
			)
			(property "MPN" "MAX31740ATA+T"
				(at 35.56 -5.08 0)
				(effects
					(font
						(size 1.27 1.27)
						(thickness 0.15)
					)
					(justify left bottom)
				)
			)
			(property "Manufacturer" "Analog Devices"
				(at 35.56 -15.24 0)
				(effects
					(font
						(size 1.27 1.27)
						(thickness 0.15)
					)
					(justify left bottom)
					(hide yes)
				)
			)
			(property "Author" "Antmicro"
				(at 35.56 -17.78 0)
				(effects
					(font
						(size 1.27 1.27)
						(thickness 0.15)
					)
					(justify left bottom)
					(hide yes)
				)
			)
			(property "License" "Apache-2.0"
				(at 35.56 -20.32 0)
				(effects
					(font
						(size 1.27 1.27)
						(thickness 0.15)
					)
					(justify left bottom)
					(hide yes)
				)
			)
			(property "ki_keywords" "SENSOR, IC, SMT"
				(at 0 0 0)
				(effects
					(font
						(size 1.27 1.27)
					)
					(hide yes)
				)
			)
			(symbol "MAX31740ATA+T_1_1"
				(rectangle
					(start 2.54 2.54)
					(end 20.32 -17.78)
					(stroke
						(width 0.254)
						(type default)
					)
					(fill
						(type background)
					)
				)
				(pin power_in line
					(at 0 0 0)
					(length 2.54)
					(name "VDD"
						(effects
							(font
								(size 1.27 1.27)
							)
						)
					)
					(number "8"
						(effects
							(font
								(size 1.27 1.27)
							)
						)
					)
				)
				(pin passive line
					(at 0 -5.08 0)
					(length 2.54)
					(name "SENSE"
						(effects
							(font
								(size 1.27 1.27)
							)
						)
					)
					(number "3"
						(effects
							(font
								(size 1.27 1.27)
							)
						)
					)
				)
				(pin passive line
					(at 0 -12.7 0)
					(length 2.54)
					(name "DMIN"
						(effects
							(font
								(size 1.27 1.27)
							)
						)
					)
					(number "1"
						(effects
							(font
								(size 1.27 1.27)
							)
						)
					)
				)
				(pin passive line
					(at 0 -15.24 0)
					(length 2.54)
					(name "D0"
						(effects
							(font
								(size 1.27 1.27)
							)
						)
					)
					(number "6"
						(effects
							(font
								(size 1.27 1.27)
							)
						)
					)
				)
				(pin output line
					(at 22.86 0 180)
					(length 2.54)
					(name "PWM_OUT"
						(effects
							(font
								(size 1.27 1.27)
							)
						)
					)
					(number "7"
						(effects
							(font
								(size 1.27 1.27)
							)
						)
					)
				)
				(pin passive line
					(at 22.86 -5.08 180)
					(length 2.54)
					(name "FREQ"
						(effects
							(font
								(size 1.27 1.27)
							)
						)
					)
					(number "5"
						(effects
							(font
								(size 1.27 1.27)
							)
						)
					)
				)
				(pin passive line
					(at 22.86 -7.62 180)
					(length 2.54)
					(name "SLOPE"
						(effects
							(font
								(size 1.27 1.27)
							)
						)
					)
					(number "2"
						(effects
							(font
								(size 1.27 1.27)
							)
						)
					)
				)
				(pin power_in line
					(at 22.86 -12.7 180)
					(length 2.54)
					(name "EP"
						(effects
							(font
								(size 1.27 1.27)
							)
						)
					)
					(number "9"
						(effects
							(font
								(size 1.27 1.27)
							)
						)
					)
				)
				(pin power_in line
					(at 22.86 -15.24 180)
					(length 2.54)
					(name "GND"
						(effects
							(font
								(size 1.27 1.27)
							)
						)
					)
					(number "4"
						(effects
							(font
								(size 1.27 1.27)
							)
						)
					)
				)
			)
		)
	(symbol "antmicroTemperatureSensorsAnalogandDigitalOutput:RT_NTC_10k_0402"
			(pin_numbers
				(hide yes)
			)
			(pin_names
				(hide yes)
			)
			(exclude_from_sim no)
			(in_bom yes)
			(on_board yes)
			(property "Reference" "RT"
				(at 20.32 -5.08 0)
				(effects
					(font
						(size 1.27 1.27)
						(thickness 0.15)
					)
					(justify left bottom)
				)
			)
			(property "Value" "RT_NTC_10k_0402"
				(at 20.32 -10.16 0)
				(effects
					(font
						(size 1.27 1.27)
						(thickness 0.15)
					)
					(justify left bottom)
					(hide yes)
				)
			)
			(property "Footprint" "antmicro-footprints:R_0402_1005Metric"
				(at 20.32 -15.24 0)
				(effects
					(font
						(size 1.27 1.27)
						(thickness 0.15)
					)
					(justify left bottom)
					(hide yes)
				)
			)
			(property "Datasheet" "https://eu.mouser.com/datasheet/2/281/r44e-522712.pdf"
				(at 20.32 -17.78 0)
				(effects
					(font
						(size 1.27 1.27)
						(thickness 0.15)
					)
					(justify left bottom)
					(hide yes)
				)
			)
			(property "Description" "10k NTC in 0402 package with 5V max voltage"
				(at 20.32 -30.48 0)
				(effects
					(font
						(size 1.27 1.27)
					)
					(justify left bottom)
					(hide yes)
				)
			)
			(property "MPN" "NCP15XH103F03RC"
				(at 20.32 -22.86 0)
				(effects
					(font
						(size 1.27 1.27)
					)
					(justify left bottom)
					(hide yes)
				)
			)
			(property "Manufacturer" "Murata"
				(at 20.32 -20.32 0)
				(effects
					(font
						(size 1.27 1.27)
					)
					(justify left bottom)
					(hide yes)
				)
			)
			(property "License" "Apache-2.0"
				(at 20.32 -27.94 0)
				(effects
					(font
						(size 1.27 1.27)
					)
					(justify left bottom)
					(hide yes)
				)
			)
			(property "Author" "Antmicro"
				(at 20.32 -25.4 0)
				(effects
					(font
						(size 1.27 1.27)
					)
					(justify left bottom)
					(hide yes)
				)
			)
			(property "Val" "10k"
				(at 20.32 -7.62 0)
				(effects
					(font
						(size 1.27 1.27)
					)
					(justify left bottom)
				)
			)
			(property "Voltage" "5V"
				(at 20.32 -12.7 0)
				(effects
					(font
						(size 1.27 1.27)
					)
					(justify left bottom)
					(hide yes)
				)
			)
			(property "ki_keywords" "THERMISTOR, NTC"
				(at 0 0 0)
				(effects
					(font
						(size 1.27 1.27)
					)
					(hide yes)
				)
			)
			(symbol "RT_NTC_10k_0402_0_1"
				(rectangle
					(start 0.635 0.889)
					(end 4.445 -0.889)
					(stroke
						(width 0.254)
						(type default)
					)
					(fill
						(type none)
					)
				)
			)
			(symbol "RT_NTC_10k_0402_1_1"
				(polyline
					(pts
						(xy 4.318 1.524) (xy 1.27 -1.524) (xy 0.508 -1.524)
					)
					(stroke
						(width 0.254)
						(type default)
					)
					(fill
						(type none)
					)
				)
				(pin passive line
					(at 0 0 0)
					(length 0.635)
					(name "~"
						(effects
							(font
								(size 1.27 1.27)
							)
						)
					)
					(number "1"
						(effects
							(font
								(size 1.27 1.27)
							)
						)
					)
				)
				(pin passive line
					(at 5.08 0 180)
					(length 0.635)
					(name "~"
						(effects
							(font
								(size 1.27 1.27)
							)
						)
					)
					(number "2"
						(effects
							(font
								(size 1.27 1.27)
							)
						)
					)
				)
			)
		)
	(symbol "antmicroTestPoints:TP_0.75mm_SMD"
			(pin_names
				(hide yes)
			)
			(exclude_from_sim no)
			(in_bom no)
			(on_board yes)
			(property "Reference" "TP"
				(at 10.16 -1.27 0)
				(effects
					(font
						(size 1.27 1.27)
						(thickness 0.15)
					)
					(justify left bottom)
				)
			)
			(property "Value" "TP_0.75mm_SMD"
				(at 10.16 -3.81 0)
				(effects
					(font
						(size 1.27 1.27)
						(thickness 0.15)
					)
					(justify left bottom)
					(hide yes)
				)
			)
			(property "Footprint" "antmicro-footprints:TP_SMD_0.75mm"
				(at 10.16 -6.35 0)
				(effects
					(font
						(size 1.27 1.27)
						(thickness 0.15)
					)
					(justify left bottom)
					(hide yes)
				)
			)
			(property "Datasheet" ""
				(at 17.78 -12.7 0)
				(effects
					(font
						(size 1.27 1.27)
						(thickness 0.15)
					)
					(justify left bottom)
					(hide yes)
				)
			)
			(property "Description" "SMT test point"
				(at 10.795 -13.97 0)
				(effects
					(font
						(size 1.27 1.27)
					)
					(justify left bottom)
					(hide yes)
				)
			)
			(property "MPN" ""
				(at 10.795 -11.43 0)
				(effects
					(font
						(size 1.27 1.27)
						(thickness 0.15)
					)
					(justify left bottom)
					(hide yes)
				)
			)
			(property "Manufacturer" ""
				(at 10.795 -6.35 0)
				(effects
					(font
						(size 1.27 1.27)
						(thickness 0.15)
					)
					(justify left bottom)
					(hide yes)
				)
			)
			(property "Author" "Antmicro"
				(at 10.16 -8.89 0)
				(effects
					(font
						(size 1.27 1.27)
						(thickness 0.15)
					)
					(justify left bottom)
					(hide yes)
				)
			)
			(property "License" "Apache-2.0"
				(at 10.16 -11.43 0)
				(effects
					(font
						(size 1.27 1.27)
						(thickness 0.15)
					)
					(justify left bottom)
					(hide yes)
				)
			)
			(property "ki_keywords" "TESTPOINT"
				(at 0 0 0)
				(effects
					(font
						(size 1.27 1.27)
					)
					(hide yes)
				)
			)
			(symbol "TP_0.75mm_SMD_1_1"
				(circle
					(center 3.175 0)
					(radius 0.635)
					(stroke
						(width 0.254)
						(type default)
					)
					(fill
						(type none)
					)
				)
				(pin passive line
					(at 0 0 0)
					(length 2.54)
					(name "1"
						(effects
							(font
								(size 1.27 1.27)
							)
						)
					)
					(number "1"
						(effects
							(font
								(size 1.27 1.27)
							)
						)
					)
				)
			)
		)
	(symbol "antmicroTestPoints:TP_1mm_SMD"
			(pin_names
				(hide yes)
			)
			(exclude_from_sim no)
			(in_bom no)
			(on_board yes)
			(property "Reference" "TP"
				(at 15.24 -5.08 0)
				(effects
					(font
						(size 1.27 1.27)
						(thickness 0.15)
					)
					(justify left bottom)
				)
			)
			(property "Value" "TP_1mm_SMD"
				(at 15.24 -7.62 0)
				(effects
					(font
						(size 1.27 1.27)
						(thickness 0.15)
					)
					(justify left bottom)
					(hide yes)
				)
			)
			(property "Footprint" "antmicro-footprints:TP_SMD_1mm"
				(at 15.24 -10.16 0)
				(effects
					(font
						(size 1.27 1.27)
						(thickness 0.15)
					)
					(justify left bottom)
					(hide yes)
				)
			)
			(property "Datasheet" ""
				(at 17.78 -12.7 0)
				(effects
					(font
						(size 1.27 1.27)
						(thickness 0.15)
					)
					(justify left bottom)
					(hide yes)
				)
			)
			(property "Description" "Test point 1mm SMD"
				(at 15.24 -20.32 0)
				(effects
					(font
						(size 1.27 1.27)
					)
					(justify left bottom)
					(hide yes)
				)
			)
			(property "MPN" ""
				(at 0 0 0)
				(effects
					(font
						(size 1.27 1.27)
					)
					(hide yes)
				)
			)
			(property "Manufacturer" ""
				(at 0 0 0)
				(effects
					(font
						(size 1.27 1.27)
					)
					(hide yes)
				)
			)
			(property "Author" "Antmicro"
				(at 15.24 -15.24 0)
				(effects
					(font
						(size 1.27 1.27)
						(thickness 0.15)
					)
					(justify left bottom)
					(hide yes)
				)
			)
			(property "License" "Apache-2.0"
				(at 15.24 -17.78 0)
				(effects
					(font
						(size 1.27 1.27)
						(thickness 0.15)
					)
					(justify left bottom)
					(hide yes)
				)
			)
			(property "ki_keywords" "TESTPOINT"
				(at 0 0 0)
				(effects
					(font
						(size 1.27 1.27)
					)
					(hide yes)
				)
			)
			(symbol "TP_1mm_SMD_1_1"
				(circle
					(center 3.175 0)
					(radius 0.635)
					(stroke
						(width 0.254)
						(type default)
					)
					(fill
						(type none)
					)
				)
				(pin passive line
					(at 0 0 0)
					(length 2.54)
					(name "1"
						(effects
							(font
								(size 1.27 1.27)
							)
						)
					)
					(number "1"
						(effects
							(font
								(size 1.27 1.27)
							)
						)
					)
				)
			)
		)
	(symbol "antmicroTestPoints:Tag-Connect_TC2050-IDC-NL_2x5_P1.27mm"
			(exclude_from_sim no)
			(in_bom no)
			(on_board yes)
			(property "Reference" "J"
				(at 39.37 -1.27 0)
				(effects
					(font
						(size 1.27 1.27)
						(thickness 0.15)
					)
					(justify left bottom)
				)
			)
			(property "Value" "Tag-Connect_TC2050-IDC-NL_2x5_P1.27mm"
				(at 39.37 -3.81 0)
				(effects
					(font
						(size 1.27 1.27)
						(thickness 0.15)
					)
					(justify left bottom)
					(hide yes)
				)
			)
			(property "Footprint" "antmicro-footprints:Tag-Connect_TC2050-IDC-NL_2x5_P1.27mm"
				(at 39.37 -6.35 0)
				(effects
					(font
						(size 1.27 1.27)
						(thickness 0.15)
					)
					(justify left bottom)
					(hide yes)
				)
			)
			(property "Datasheet" "https://www.tag-connect.com/wp-content/uploads/bsk-pdf-manager/TC2050-IDC-NL_Datasheet_8.pdf"
				(at 39.37 -8.89 0)
				(effects
					(font
						(size 1.27 1.27)
						(thickness 0.15)
					)
					(justify left bottom)
					(hide yes)
				)
			)
			(property "Description" "Tag Connect 2x5 1.27mm terminal"
				(at 39.37 -21.59 0)
				(effects
					(font
						(size 1.27 1.27)
					)
					(justify left bottom)
					(hide yes)
				)
			)
			(property "MPN" "TC2050-IDC-NL"
				(at 39.37 -11.43 0)
				(effects
					(font
						(size 1.27 1.27)
						(thickness 0.15)
					)
					(justify left bottom)
				)
			)
			(property "Manufacturer" "Tag Connect"
				(at 39.37 -13.97 0)
				(effects
					(font
						(size 1.27 1.27)
						(thickness 0.15)
					)
					(justify left bottom)
					(hide yes)
				)
			)
			(property "Author" "Antmicro"
				(at 39.37 -16.51 0)
				(effects
					(font
						(size 1.27 1.27)
						(thickness 0.15)
					)
					(justify left bottom)
					(hide yes)
				)
			)
			(property "License" "Apache-2.0"
				(at 39.37 -19.05 0)
				(effects
					(font
						(size 1.27 1.27)
						(thickness 0.15)
					)
					(justify left bottom)
					(hide yes)
				)
			)
			(property "ki_keywords" "POGO-PIN, CONNECTOR"
				(at 0 0 0)
				(effects
					(font
						(size 1.27 1.27)
					)
					(hide yes)
				)
			)
			(symbol "Tag-Connect_TC2050-IDC-NL_2x5_P1.27mm_1_1"
				(rectangle
					(start 2.54 2.54)
					(end 29.21 -12.7)
					(stroke
						(width 0)
						(type default)
					)
					(fill
						(type background)
					)
				)
				(circle
					(center 15.113 -7.5184)
					(radius 0.4572)
					(stroke
						(width 0)
						(type default)
					)
					(fill
						(type none)
					)
				)
				(polyline
					(pts
						(xy 15.24 -8.636) (xy 17.145 -8.636) (xy 17.78 -8.001) (xy 17.78 -2.921) (xy 16.51 -1.016) (xy 15.24 -1.016)
						(xy 13.97 -2.921) (xy 13.97 -8.001) (xy 14.605 -8.636) (xy 15.24 -8.636)
					)
					(stroke
						(width 0)
						(type default)
					)
					(fill
						(type none)
					)
				)
				(circle
					(center 15.367 -3.4544)
					(radius 0.2032)
					(stroke
						(width 0)
						(type default)
					)
					(fill
						(type outline)
					)
				)
				(circle
					(center 15.367 -4.1656)
					(radius 0.2032)
					(stroke
						(width 0)
						(type default)
					)
					(fill
						(type outline)
					)
				)
				(circle
					(center 15.367 -4.9276)
					(radius 0.2032)
					(stroke
						(width 0)
						(type default)
					)
					(fill
						(type outline)
					)
				)
				(circle
					(center 15.367 -5.6388)
					(radius 0.2032)
					(stroke
						(width 0)
						(type default)
					)
					(fill
						(type outline)
					)
				)
				(circle
					(center 15.367 -6.4008)
					(radius 0.2032)
					(stroke
						(width 0)
						(type default)
					)
					(fill
						(type outline)
					)
				)
				(circle
					(center 15.875 -2.1336)
					(radius 0.4572)
					(stroke
						(width 0)
						(type default)
					)
					(fill
						(type none)
					)
				)
				(circle
					(center 16.383 -3.4544)
					(radius 0.2032)
					(stroke
						(width 0)
						(type default)
					)
					(fill
						(type outline)
					)
				)
				(circle
					(center 16.383 -4.1656)
					(radius 0.2032)
					(stroke
						(width 0)
						(type default)
					)
					(fill
						(type outline)
					)
				)
				(circle
					(center 16.383 -4.9276)
					(radius 0.2032)
					(stroke
						(width 0)
						(type default)
					)
					(fill
						(type outline)
					)
				)
				(circle
					(center 16.383 -5.6388)
					(radius 0.2032)
					(stroke
						(width 0)
						(type default)
					)
					(fill
						(type outline)
					)
				)
				(circle
					(center 16.383 -6.4008)
					(radius 0.2032)
					(stroke
						(width 0)
						(type default)
					)
					(fill
						(type outline)
					)
				)
				(circle
					(center 16.7386 -7.5184)
					(radius 0.4572)
					(stroke
						(width 0)
						(type default)
					)
					(fill
						(type none)
					)
				)
				(text "Tag-Connect"
					(at 15.875 1.651 0)
					(effects
						(font
							(size 0.7 0.7)
						)
					)
				)
				(text "ALT: 3.3V I2C/JTAG/SPI/SWD/FTDI"
					(at 16.002 -11.938 0)
					(effects
						(font
							(size 0.7 0.7)
						)
					)
				)
				(pin passive line
					(at 0 0 0)
					(length 2.54)
					(name "1"
						(effects
							(font
								(size 1.27 1.27)
							)
						)
					)
					(number "1"
						(effects
							(font
								(size 1.27 1.27)
							)
						)
					)
					(alternate "3V3" passive line)
				)
				(pin passive line
					(at 0 -2.54 0)
					(length 2.54)
					(name "2"
						(effects
							(font
								(size 1.27 1.27)
							)
						)
					)
					(number "2"
						(effects
							(font
								(size 1.27 1.27)
							)
						)
					)
					(alternate "ADBUS3" passive line)
					(alternate "I2C_NC" passive line)
					(alternate "JTAG_TMS" passive line)
					(alternate "SPI_CS" passive line)
					(alternate "SWD_NC" passive line)
				)
				(pin passive line
					(at 0 -5.08 0)
					(length 2.54)
					(name "3"
						(effects
							(font
								(size 1.27 1.27)
							)
						)
					)
					(number "3"
						(effects
							(font
								(size 1.27 1.27)
							)
						)
					)
					(alternate "GND" passive line)
				)
				(pin passive line
					(at 0 -7.62 0)
					(length 2.54)
					(name "4"
						(effects
							(font
								(size 1.27 1.27)
							)
						)
					)
					(number "4"
						(effects
							(font
								(size 1.27 1.27)
							)
						)
					)
					(alternate "ADBUS0" passive line)
					(alternate "I2C_SCL" passive line)
					(alternate "JTAG_TCK" passive line)
					(alternate "SPI_SCK" passive line)
					(alternate "SWD_CLK" passive line)
				)
				(pin passive line
					(at 0 -10.16 0)
					(length 2.54)
					(name "5"
						(effects
							(font
								(size 1.27 1.27)
							)
						)
					)
					(number "5"
						(effects
							(font
								(size 1.27 1.27)
							)
						)
					)
					(alternate "GND" passive line)
				)
				(pin passive line
					(at 31.75 0 180)
					(length 2.54)
					(name "10"
						(effects
							(font
								(size 1.27 1.27)
							)
						)
					)
					(number "10"
						(effects
							(font
								(size 1.27 1.27)
							)
						)
					)
					(alternate "ADBUS5" passive line)
					(alternate "I2C_NC" passive line)
					(alternate "JTAG_~{RESET}" passive line)
					(alternate "SPI_NC" passive line)
					(alternate "SWD_NC" passive line)
				)
				(pin passive line
					(at 31.75 -2.54 180)
					(length 2.54)
					(name "9"
						(effects
							(font
								(size 1.27 1.27)
							)
						)
					)
					(number "9"
						(effects
							(font
								(size 1.27 1.27)
							)
						)
					)
					(alternate "GND" passive line)
				)
				(pin passive line
					(at 31.75 -5.08 180)
					(length 2.54)
					(name "8"
						(effects
							(font
								(size 1.27 1.27)
							)
						)
					)
					(number "8"
						(effects
							(font
								(size 1.27 1.27)
							)
						)
					)
					(alternate "ADBUS1" passive line)
					(alternate "I2C_SDA" passive line)
					(alternate "JTAG_TDI" passive line)
					(alternate "SPI_MOSI" passive line)
					(alternate "SWD_IO" passive line)
				)
				(pin passive line
					(at 31.75 -7.62 180)
					(length 2.54)
					(name "7"
						(effects
							(font
								(size 1.27 1.27)
							)
						)
					)
					(number "7"
						(effects
							(font
								(size 1.27 1.27)
							)
						)
					)
					(alternate "NC" no_connect line)
				)
				(pin passive line
					(at 31.75 -10.16 180)
					(length 2.54)
					(name "6"
						(effects
							(font
								(size 1.27 1.27)
							)
						)
					)
					(number "6"
						(effects
							(font
								(size 1.27 1.27)
							)
						)
					)
					(alternate "ADBUS2" passive line)
					(alternate "I2C_SDA" passive line)
					(alternate "JTAG_TDO" passive line)
					(alternate "SPI_MISO" passive line)
					(alternate "SWD_IO" passive line)
				)
			)
		)
	(symbol "antmicroTransistorsBipolarSingle:DTC014T_SOT-416"
			(pin_names
				(offset 0)
			)
			(exclude_from_sim no)
			(in_bom yes)
			(on_board yes)
			(property "Reference" "Q"
				(at 25.4 -5.08 0)
				(effects
					(font
						(size 1.27 1.27)
						(thickness 0.15)
					)
					(justify left bottom)
				)
			)
			(property "Value" "DTC014T_SOT-416"
				(at 25.4 -7.62 0)
				(effects
					(font
						(size 1.27 1.27)
						(thickness 0.15)
					)
					(justify left bottom)
					(hide yes)
				)
			)
			(property "Footprint" "antmicro-footprints:SOT-416"
				(at 25.4 -10.16 0)
				(effects
					(font
						(size 1.27 1.27)
						(thickness 0.15)
					)
					(justify left bottom)
					(hide yes)
				)
			)
			(property "Datasheet" "https://www.rohm.com/datasheet?p=DTC014TEB&dist=Mouser&media=referral&source=mouser.com&campaign=Mouser"
				(at 25.4 -12.7 0)
				(effects
					(font
						(size 1.27 1.27)
						(thickness 0.15)
					)
					(justify left bottom)
					(hide yes)
				)
			)
			(property "Description" "Bipolar (BJT) Single Transistor with built-in base resistor, NPN, 50V, 100mA, 150mW, SOT-416FL, Surface Mount"
				(at 25.4 -25.4 0)
				(effects
					(font
						(size 1.27 1.27)
					)
					(justify left bottom)
					(hide yes)
				)
			)
			(property "Manufacturer" "ROHM Semiconductor"
				(at 25.4 -15.24 0)
				(effects
					(font
						(size 1.27 1.27)
						(thickness 0.15)
					)
					(justify left bottom)
					(hide yes)
				)
			)
			(property "MPN" "DTC014TEBTL"
				(at 25.4 -17.78 0)
				(effects
					(font
						(size 1.27 1.27)
						(thickness 0.15)
					)
					(justify left bottom)
				)
			)
			(property "Author" "Antmicro"
				(at 25.4 -20.32 0)
				(effects
					(font
						(size 1.27 1.27)
						(thickness 0.15)
					)
					(justify left bottom)
					(hide yes)
				)
			)
			(property "License" "Apache-2.0"
				(at 25.4 -22.86 0)
				(effects
					(font
						(size 1.27 1.27)
						(thickness 0.15)
					)
					(justify left bottom)
					(hide yes)
				)
			)
			(property "ki_keywords" "SMT, TRANSISTOR, SEMICONDUCTOR, BIPOLAR, NPN"
				(at 0 0 0)
				(effects
					(font
						(size 1.27 1.27)
					)
					(hide yes)
				)
			)
			(symbol "DTC014T_SOT-416_0_1"
				(polyline
					(pts
						(xy 2.54 0) (xy 3.175 0)
					)
					(stroke
						(width 0.254)
						(type default)
					)
					(fill
						(type none)
					)
				)
				(polyline
					(pts
						(xy 5.08 0) (xy 5.588 0)
					)
					(stroke
						(width 0.254)
						(type default)
					)
					(fill
						(type none)
					)
				)
				(circle
					(center 5.588 0)
					(radius 3.2528)
					(stroke
						(width 0.254)
						(type default)
					)
					(fill
						(type background)
					)
				)
				(polyline
					(pts
						(xy 5.715 1.905) (xy 5.715 -1.905) (xy 5.715 -1.905)
					)
					(stroke
						(width 0.508)
						(type default)
					)
					(fill
						(type none)
					)
				)
				(polyline
					(pts
						(xy 5.715 0.635) (xy 7.62 2.54)
					)
					(stroke
						(width 0.254)
						(type default)
					)
					(fill
						(type none)
					)
				)
				(polyline
					(pts
						(xy 5.715 -0.635) (xy 7.62 -2.54) (xy 7.62 -2.54)
					)
					(stroke
						(width 0.254)
						(type default)
					)
					(fill
						(type none)
					)
				)
				(polyline
					(pts
						(xy 6.35 -1.778) (xy 6.858 -1.27) (xy 7.366 -2.286) (xy 6.35 -1.778) (xy 6.35 -1.778)
					)
					(stroke
						(width 0)
						(type default)
					)
					(fill
						(type outline)
					)
				)
			)
			(symbol "DTC014T_SOT-416_1_1"
				(rectangle
					(start 3.302 0.381)
					(end 4.953 -0.381)
					(stroke
						(width 0.254)
						(type default)
					)
					(fill
						(type none)
					)
				)
				(text "10k"
					(at 3.302 0.508 0)
					(effects
						(font
							(size 0.635 0.635)
							(thickness 0.15)
						)
						(justify left bottom)
					)
				)
				(pin input line
					(at 0 0 0)
					(length 2.54)
					(name "B"
						(effects
							(font
								(size 1.27 1.27)
							)
						)
					)
					(number "1"
						(effects
							(font
								(size 1.27 1.27)
							)
						)
					)
				)
				(pin passive line
					(at 7.62 5.08 270)
					(length 2.54)
					(name "C"
						(effects
							(font
								(size 1.27 1.27)
							)
						)
					)
					(number "3"
						(effects
							(font
								(size 1.27 1.27)
							)
						)
					)
				)
				(pin passive line
					(at 7.62 -5.08 90)
					(length 2.54)
					(name "E"
						(effects
							(font
								(size 1.27 1.27)
							)
						)
					)
					(number "2"
						(effects
							(font
								(size 1.27 1.27)
							)
						)
					)
				)
			)
		)
	(symbol "antmicroTransistorsFETsMOSFETsSingle:2N7002_SOT-23-3"
			(pin_names
				(offset 0)
			)
			(exclude_from_sim no)
			(in_bom yes)
			(on_board yes)
			(property "Reference" "Q"
				(at 22.86 -5.08 0)
				(effects
					(font
						(size 1.27 1.27)
						(thickness 0.15)
					)
					(justify left bottom)
				)
			)
			(property "Value" "2N7002_SOT-23-3"
				(at 22.86 -7.62 0)
				(effects
					(font
						(size 1.27 1.27)
						(thickness 0.15)
					)
					(justify left bottom)
					(hide yes)
				)
			)
			(property "Footprint" "antmicro-footprints:SOT-23-3"
				(at 22.86 -10.16 0)
				(effects
					(font
						(size 1.27 1.27)
						(thickness 0.15)
					)
					(justify left bottom)
					(hide yes)
				)
			)
			(property "Datasheet" "https://www.onsemi.com/pub/Collateral/NDS7002A-D.PDF"
				(at 22.86 -12.7 0)
				(effects
					(font
						(size 1.27 1.27)
						(thickness 0.15)
					)
					(justify left bottom)
					(hide yes)
				)
			)
			(property "Description" "Power MOSFET, N Channel, 60 V, 115 mA, 1.2 ohm, SOT-23, Surface Mount"
				(at 22.86 -25.4 0)
				(effects
					(font
						(size 1.27 1.27)
					)
					(justify left bottom)
					(hide yes)
				)
			)
			(property "MPN" "2N7002"
				(at 22.86 -15.24 0)
				(effects
					(font
						(size 1.27 1.27)
						(thickness 0.15)
					)
					(justify left bottom)
				)
			)
			(property "Manufacturer" "ON Semiconductor"
				(at 22.86 -17.78 0)
				(effects
					(font
						(size 1.27 1.27)
						(thickness 0.15)
					)
					(justify left bottom)
					(hide yes)
				)
			)
			(property "Author" "Antmicro"
				(at 22.86 -20.32 0)
				(effects
					(font
						(size 1.27 1.27)
						(thickness 0.15)
					)
					(justify left bottom)
					(hide yes)
				)
			)
			(property "License" "Apache-2.0"
				(at 22.86 -22.86 0)
				(effects
					(font
						(size 1.27 1.27)
						(thickness 0.15)
					)
					(justify left bottom)
					(hide yes)
				)
			)
			(property "ki_keywords" "SMT, TRANSISTOR, SEMICONDUCTOR, NMOS"
				(at 0 0 0)
				(effects
					(font
						(size 1.27 1.27)
					)
					(hide yes)
				)
			)
			(symbol "2N7002_SOT-23-3_1_1"
				(polyline
					(pts
						(xy 2.54 0) (xy 4.572 0) (xy 4.572 3.937)
					)
					(stroke
						(width 0.254)
						(type default)
					)
					(fill
						(type none)
					)
				)
				(polyline
					(pts
						(xy 5.08 4.445) (xy 5.08 3.429)
					)
					(stroke
						(width 0.254)
						(type default)
					)
					(fill
						(type background)
					)
				)
				(polyline
					(pts
						(xy 5.08 2.54) (xy 5.08 3.048)
					)
					(stroke
						(width 0.254)
						(type default)
					)
					(fill
						(type background)
					)
				)
				(polyline
					(pts
						(xy 5.08 2.54) (xy 5.08 2.032)
					)
					(stroke
						(width 0.254)
						(type default)
					)
					(fill
						(type background)
					)
				)
				(polyline
					(pts
						(xy 5.08 2.54) (xy 5.842 3.048) (xy 5.842 2.032) (xy 5.08 2.54)
					)
					(stroke
						(width 0.254)
						(type default)
					)
					(fill
						(type outline)
					)
				)
				(polyline
					(pts
						(xy 5.08 1.143) (xy 5.08 1.651)
					)
					(stroke
						(width 0.254)
						(type default)
					)
					(fill
						(type background)
					)
				)
				(polyline
					(pts
						(xy 5.08 1.143) (xy 5.08 0.635)
					)
					(stroke
						(width 0.254)
						(type default)
					)
					(fill
						(type background)
					)
				)
				(circle
					(center 6.35 2.54)
					(radius 3.302)
					(stroke
						(width 0.254)
						(type default)
					)
					(fill
						(type background)
					)
				)
				(polyline
					(pts
						(xy 7.493 0.635) (xy 8.636 0.635) (xy 8.636 3.937) (xy 8.636 4.445) (xy 7.493 4.445)
					)
					(stroke
						(width 0.254)
						(type default)
					)
					(fill
						(type background)
					)
				)
				(polyline
					(pts
						(xy 7.62 6.35) (xy 7.62 3.937) (xy 5.08 3.937)
					)
					(stroke
						(width 0.254)
						(type default)
					)
					(fill
						(type none)
					)
				)
				(circle
					(center 7.62 4.445)
					(radius 0.127)
					(stroke
						(width 0.254)
						(type default)
					)
					(fill
						(type background)
					)
				)
				(polyline
					(pts
						(xy 7.62 1.143) (xy 5.08 1.143)
					)
					(stroke
						(width 0.254)
						(type default)
					)
					(fill
						(type background)
					)
				)
				(circle
					(center 7.62 1.143)
					(radius 0.127)
					(stroke
						(width 0.254)
						(type default)
					)
					(fill
						(type background)
					)
				)
				(circle
					(center 7.62 0.635)
					(radius 0.127)
					(stroke
						(width 0.254)
						(type default)
					)
					(fill
						(type background)
					)
				)
				(polyline
					(pts
						(xy 7.62 -1.27) (xy 7.62 2.54) (xy 5.08 2.54)
					)
					(stroke
						(width 0.254)
						(type default)
					)
					(fill
						(type none)
					)
				)
				(polyline
					(pts
						(xy 8.636 3.048) (xy 8.128 2.286) (xy 9.144 2.286) (xy 8.636 3.048)
					)
					(stroke
						(width 0.254)
						(type default)
					)
					(fill
						(type outline)
					)
				)
				(polyline
					(pts
						(xy 9.144 3.048) (xy 8.128 3.048)
					)
					(stroke
						(width 0.254)
						(type default)
					)
					(fill
						(type background)
					)
				)
				(pin input line
					(at 0 0 0)
					(length 2.54)
					(name "G"
						(effects
							(font
								(size 1.27 1.27)
							)
						)
					)
					(number "1"
						(effects
							(font
								(size 1.27 1.27)
							)
						)
					)
				)
				(pin passive line
					(at 7.62 8.89 270)
					(length 2.54)
					(name "D"
						(effects
							(font
								(size 1.27 1.27)
							)
						)
					)
					(number "3"
						(effects
							(font
								(size 1.27 1.27)
							)
						)
					)
				)
				(pin passive line
					(at 7.62 -3.81 90)
					(length 2.54)
					(name "S"
						(effects
							(font
								(size 1.27 1.27)
							)
						)
					)
					(number "2"
						(effects
							(font
								(size 1.27 1.27)
							)
						)
					)
				)
			)
		)
	(symbol "antmicroTransistorsFETsMOSFETsSingle:SQS401EN-T1_BE3"
			(pin_names
				(offset 0)
			)
			(exclude_from_sim no)
			(in_bom yes)
			(on_board yes)
			(property "Reference" "Q"
				(at 15.24 -5.08 0)
				(effects
					(font
						(size 1.27 1.27)
						(thickness 0.15)
					)
					(justify left bottom)
				)
			)
			(property "Value" "SQS401EN-T1_BE3"
				(at 15.24 -10.16 0)
				(effects
					(font
						(size 1.27 1.27)
						(thickness 0.15)
					)
					(justify left bottom)
					(hide yes)
				)
			)
			(property "Footprint" "antmicro-footprints:Vishay_PowerPAK_1212-8_Single"
				(at 15.24 -12.7 0)
				(effects
					(font
						(size 1.27 1.27)
						(thickness 0.15)
					)
					(justify left bottom)
					(hide yes)
				)
			)
			(property "Datasheet" "https://www.vishay.com/docs/65529/sqs401en.pdf"
				(at 15.24 -15.24 0)
				(effects
					(font
						(size 1.27 1.27)
						(thickness 0.15)
					)
					(justify left bottom)
					(hide yes)
				)
			)
			(property "Description" "MOSFET, P Channel, 40 V, 16A, 0.047 ohm, PowerPAK 1212-8, Surface Mount"
				(at 15.24 -25.4 0)
				(effects
					(font
						(size 1.27 1.27)
					)
					(justify left bottom)
					(hide yes)
				)
			)
			(property "MPN" "SQS401EN-T1_BE3"
				(at 15.24 -7.62 0)
				(effects
					(font
						(size 1.27 1.27)
						(thickness 0.15)
					)
					(justify left bottom)
				)
			)
			(property "Manufacturer" "Vishay"
				(at 15.24 -17.78 0)
				(effects
					(font
						(size 1.27 1.27)
						(thickness 0.15)
					)
					(justify left bottom)
					(hide yes)
				)
			)
			(property "Author" "Antmicro"
				(at 15.24 -20.32 0)
				(effects
					(font
						(size 1.27 1.27)
						(thickness 0.15)
					)
					(justify left bottom)
					(hide yes)
				)
			)
			(property "License" "Apache-2.0"
				(at 15.24 -22.86 0)
				(effects
					(font
						(size 1.27 1.27)
						(thickness 0.15)
					)
					(justify left bottom)
					(hide yes)
				)
			)
			(property "ki_keywords" "SMT, TRANSISTOR, SEMICONDUCTOR, MOSFET, PMOS"
				(at 0 0 0)
				(effects
					(font
						(size 1.27 1.27)
					)
					(hide yes)
				)
			)
			(symbol "SQS401EN-T1_BE3_1_1"
				(polyline
					(pts
						(xy 1.27 0) (xy 3.302 0) (xy 3.302 3.937)
					)
					(stroke
						(width 0.254)
						(type default)
					)
					(fill
						(type none)
					)
				)
				(polyline
					(pts
						(xy 3.81 4.445) (xy 3.81 3.429)
					)
					(stroke
						(width 0.254)
						(type default)
					)
					(fill
						(type background)
					)
				)
				(polyline
					(pts
						(xy 3.81 2.54) (xy 3.81 3.048)
					)
					(stroke
						(width 0.254)
						(type default)
					)
					(fill
						(type background)
					)
				)
				(polyline
					(pts
						(xy 3.81 2.54) (xy 3.81 2.032)
					)
					(stroke
						(width 0.254)
						(type default)
					)
					(fill
						(type background)
					)
				)
				(polyline
					(pts
						(xy 3.81 1.143) (xy 3.81 1.651)
					)
					(stroke
						(width 0.254)
						(type default)
					)
					(fill
						(type background)
					)
				)
				(polyline
					(pts
						(xy 3.81 1.143) (xy 3.81 0.635)
					)
					(stroke
						(width 0.254)
						(type default)
					)
					(fill
						(type background)
					)
				)
				(circle
					(center 5.08 2.54)
					(radius 3.302)
					(stroke
						(width 0.254)
						(type default)
					)
					(fill
						(type background)
					)
				)
				(polyline
					(pts
						(xy 6.096 2.54) (xy 5.334 2.032) (xy 5.334 3.048) (xy 6.096 2.54)
					)
					(stroke
						(width 0.254)
						(type default)
					)
					(fill
						(type outline)
					)
				)
				(polyline
					(pts
						(xy 6.223 0.635) (xy 7.366 0.635) (xy 7.366 3.937) (xy 7.366 4.445) (xy 6.223 4.445)
					)
					(stroke
						(width 0.254)
						(type default)
					)
					(fill
						(type none)
					)
				)
				(polyline
					(pts
						(xy 6.35 6.35) (xy 6.35 3.937) (xy 3.81 3.937)
					)
					(stroke
						(width 0.254)
						(type default)
					)
					(fill
						(type none)
					)
				)
				(circle
					(center 6.35 4.445)
					(radius 0.127)
					(stroke
						(width 0.254)
						(type default)
					)
					(fill
						(type background)
					)
				)
				(polyline
					(pts
						(xy 6.35 1.143) (xy 3.81 1.143)
					)
					(stroke
						(width 0.254)
						(type default)
					)
					(fill
						(type background)
					)
				)
				(circle
					(center 6.35 1.143)
					(radius 0.127)
					(stroke
						(width 0.254)
						(type default)
					)
					(fill
						(type background)
					)
				)
				(circle
					(center 6.35 0.635)
					(radius 0.127)
					(stroke
						(width 0.254)
						(type default)
					)
					(fill
						(type background)
					)
				)
				(polyline
					(pts
						(xy 6.35 -1.27) (xy 6.35 2.54) (xy 3.81 2.54)
					)
					(stroke
						(width 0.254)
						(type default)
					)
					(fill
						(type none)
					)
				)
				(polyline
					(pts
						(xy 7.366 2.286) (xy 7.874 3.048) (xy 6.858 3.048) (xy 7.366 2.286)
					)
					(stroke
						(width 0.254)
						(type default)
					)
					(fill
						(type outline)
					)
				)
				(polyline
					(pts
						(xy 7.874 2.286) (xy 6.858 2.286)
					)
					(stroke
						(width 0.254)
						(type default)
					)
					(fill
						(type background)
					)
				)
				(pin passive line
					(at 0 0 0)
					(length 2.54)
					(name "G"
						(effects
							(font
								(size 1.27 1.27)
							)
						)
					)
					(number "4"
						(effects
							(font
								(size 1.27 1.27)
							)
						)
					)
				)
				(pin passive line
					(at 6.35 7.62 270)
					(length 2.54)
					(name "D"
						(effects
							(font
								(size 1.27 1.27)
							)
						)
					)
					(number "5"
						(effects
							(font
								(size 1.27 1.27)
							)
						)
					)
				)
				(pin passive line
					(at 6.35 -2.54 90)
					(length 2.54)
					(name "S"
						(effects
							(font
								(size 1.27 1.27)
							)
						)
					)
					(number "1"
						(effects
							(font
								(size 1.27 1.27)
							)
						)
					)
				)
				(pin passive line
					(at 6.35 -2.54 90)
					(length 2.54)
					(hide yes)
					(name "S"
						(effects
							(font
								(size 1.27 1.27)
							)
						)
					)
					(number "2"
						(effects
							(font
								(size 1.27 1.27)
							)
						)
					)
				)
				(pin passive line
					(at 6.35 -2.54 90)
					(length 2.54)
					(hide yes)
					(name "S"
						(effects
							(font
								(size 1.27 1.27)
							)
						)
					)
					(number "3"
						(effects
							(font
								(size 1.27 1.27)
							)
						)
					)
				)
			)
		)
	(symbol "antmicroUSBConnectors:USB-C_GCT_USB4105-GF-A"
			(exclude_from_sim no)
			(in_bom yes)
			(on_board yes)
			(property "Reference" "J"
				(at 38.1 -2.54 0)
				(effects
					(font
						(size 1.27 1.27)
						(thickness 0.15)
					)
					(justify left bottom)
				)
			)
			(property "Value" "USB-C_GCT_USB4105-GF-A"
				(at 38.1 -5.08 0)
				(effects
					(font
						(size 1.27 1.27)
						(thickness 0.15)
					)
					(justify left bottom)
					(hide yes)
				)
			)
			(property "Footprint" "antmicro-footprints:USB-C_Receptacle_GCT_USB4105-GF-A"
				(at 38.1 -7.62 0)
				(effects
					(font
						(size 1.27 1.27)
						(thickness 0.15)
					)
					(justify left bottom)
					(hide yes)
				)
			)
			(property "Datasheet" "https://gct.co/files/drawings/usb4105.pdf"
				(at 38.1 -10.16 0)
				(effects
					(font
						(size 1.27 1.27)
						(thickness 0.15)
					)
					(justify left bottom)
					(hide yes)
				)
			)
			(property "Description" "USB-C (USB TYPE-C) USB 2.0 Receptacle Connector 24 (16+8 Dummy) Position Surface Mount, Right Angle"
				(at 38.1 -22.86 0)
				(effects
					(font
						(size 1.27 1.27)
					)
					(justify left bottom)
					(hide yes)
				)
			)
			(property "Manufacturer" "GCT"
				(at 38.1 -12.7 0)
				(effects
					(font
						(size 1.27 1.27)
						(thickness 0.15)
					)
					(justify left bottom)
					(hide yes)
				)
			)
			(property "MPN" "USB4105-GF-A"
				(at 38.1 -15.24 0)
				(effects
					(font
						(size 1.27 1.27)
						(thickness 0.15)
					)
					(justify left bottom)
				)
			)
			(property "Author" "Antmicro"
				(at 38.1 -17.78 0)
				(effects
					(font
						(size 1.27 1.27)
						(thickness 0.15)
					)
					(justify left bottom)
					(hide yes)
				)
			)
			(property "License" "Apache-2.0"
				(at 38.1 -20.32 0)
				(effects
					(font
						(size 1.27 1.27)
						(thickness 0.15)
					)
					(justify left bottom)
					(hide yes)
				)
			)
			(property "ki_keywords" "USB, CONNECTOR, SMT, HORIZONTAL"
				(at 0 0 0)
				(effects
					(font
						(size 1.27 1.27)
					)
					(hide yes)
				)
			)
			(symbol "USB-C_GCT_USB4105-GF-A_1_1"
				(rectangle
					(start -22.86 2.54)
					(end -3.81 -38.1)
					(stroke
						(width 0.254)
						(type default)
					)
					(fill
						(type background)
					)
				)
				(circle
					(center -20.066 -18.034)
					(radius 0.284)
					(stroke
						(width 0.254)
						(type default)
					)
					(fill
						(type outline)
					)
				)
				(polyline
					(pts
						(xy -19.812 -16.383) (xy -19.177 -15.24) (xy -18.542 -16.383) (xy -19.812 -16.383)
					)
					(stroke
						(width 0.254)
						(type default)
					)
					(fill
						(type outline)
					)
				)
				(polyline
					(pts
						(xy -19.177 -19.558) (xy -18.288 -18.669) (xy -18.288 -18.034)
					)
					(stroke
						(width 0.254)
						(type default)
					)
					(fill
						(type background)
					)
				)
				(polyline
					(pts
						(xy -19.177 -19.939) (xy -20.066 -19.05) (xy -20.066 -18.415)
					)
					(stroke
						(width 0.254)
						(type default)
					)
					(fill
						(type background)
					)
				)
				(polyline
					(pts
						(xy -19.177 -20.701) (xy -19.177 -16.383)
					)
					(stroke
						(width 0.254)
						(type default)
					)
					(fill
						(type background)
					)
				)
				(circle
					(center -19.177 -20.828)
					(radius 0.5236)
					(stroke
						(width 0.254)
						(type default)
					)
					(fill
						(type outline)
					)
				)
				(rectangle
					(start -18.669 -18.034)
					(end -17.907 -17.272)
					(stroke
						(width 0.254)
						(type default)
					)
					(fill
						(type outline)
					)
				)
				(polyline
					(pts
						(xy -16.51 -21.59) (xy -16.51 -13.97)
					)
					(stroke
						(width 0.254)
						(type default)
					)
					(fill
						(type background)
					)
				)
				(rectangle
					(start -15.24 -21.59)
					(end -13.97 -13.97)
					(stroke
						(width 0.254)
						(type default)
					)
					(fill
						(type outline)
					)
				)
				(arc
					(start -15.24 -13.97)
					(mid -14.605 -13.3377)
					(end -13.97 -13.97)
					(stroke
						(width 0.254)
						(type default)
					)
					(fill
						(type outline)
					)
				)
				(arc
					(start -15.24 -13.97)
					(mid -14.605 -13.3377)
					(end -13.97 -13.97)
					(stroke
						(width 0.254)
						(type default)
					)
					(fill
						(type background)
					)
				)
				(arc
					(start -16.51 -13.97)
					(mid -14.605 -12.0733)
					(end -12.7 -13.97)
					(stroke
						(width 0.254)
						(type default)
					)
					(fill
						(type background)
					)
				)
				(arc
					(start -12.7 -21.59)
					(mid -14.605 -23.4867)
					(end -16.51 -21.59)
					(stroke
						(width 0.254)
						(type default)
					)
					(fill
						(type background)
					)
				)
				(arc
					(start -13.97 -21.59)
					(mid -14.605 -22.2223)
					(end -15.24 -21.59)
					(stroke
						(width 0.254)
						(type default)
					)
					(fill
						(type outline)
					)
				)
				(arc
					(start -13.97 -21.59)
					(mid -14.605 -22.2223)
					(end -15.24 -21.59)
					(stroke
						(width 0.254)
						(type default)
					)
					(fill
						(type background)
					)
				)
				(polyline
					(pts
						(xy -12.7 -13.97) (xy -12.7 -21.59)
					)
					(stroke
						(width 0.254)
						(type default)
					)
					(fill
						(type background)
					)
				)
				(pin power_in line
					(at 0 0 180)
					(length 3.81)
					(name "VBUS"
						(effects
							(font
								(size 1.27 1.27)
							)
						)
					)
					(number "A4"
						(effects
							(font
								(size 1.27 1.27)
							)
						)
					)
				)
				(pin passive line
					(at 0 0 180)
					(length 3.81)
					(hide yes)
					(name "VBUS"
						(effects
							(font
								(size 1.27 1.27)
							)
						)
					)
					(number "A9"
						(effects
							(font
								(size 1.27 1.27)
							)
						)
					)
				)
				(pin passive line
					(at 0 0 180)
					(length 3.81)
					(hide yes)
					(name "VBUS"
						(effects
							(font
								(size 1.27 1.27)
							)
						)
					)
					(number "B4"
						(effects
							(font
								(size 1.27 1.27)
							)
						)
					)
				)
				(pin passive line
					(at 0 0 180)
					(length 3.81)
					(hide yes)
					(name "VBUS"
						(effects
							(font
								(size 1.27 1.27)
							)
						)
					)
					(number "B9"
						(effects
							(font
								(size 1.27 1.27)
							)
						)
					)
				)
				(pin bidirectional line
					(at 0 -5.08 180)
					(length 3.81)
					(name "CC_{1}"
						(effects
							(font
								(size 1.27 1.27)
							)
						)
					)
					(number "A5"
						(effects
							(font
								(size 1.27 1.27)
							)
						)
					)
				)
				(pin bidirectional line
					(at 0 -7.62 180)
					(length 3.81)
					(name "CC_{2}"
						(effects
							(font
								(size 1.27 1.27)
							)
						)
					)
					(number "B5"
						(effects
							(font
								(size 1.27 1.27)
							)
						)
					)
				)
				(pin bidirectional line
					(at 0 -12.7 180)
					(length 3.81)
					(name "D_{A}+"
						(effects
							(font
								(size 1.27 1.27)
							)
						)
					)
					(number "A6"
						(effects
							(font
								(size 1.27 1.27)
							)
						)
					)
				)
				(pin bidirectional line
					(at 0 -15.24 180)
					(length 3.81)
					(name "D_{A}-"
						(effects
							(font
								(size 1.27 1.27)
							)
						)
					)
					(number "A7"
						(effects
							(font
								(size 1.27 1.27)
							)
						)
					)
				)
				(pin bidirectional line
					(at 0 -17.78 180)
					(length 3.81)
					(name "D_{B}+"
						(effects
							(font
								(size 1.27 1.27)
							)
						)
					)
					(number "B6"
						(effects
							(font
								(size 1.27 1.27)
							)
						)
					)
				)
				(pin bidirectional line
					(at 0 -20.32 180)
					(length 3.81)
					(name "D_{B}-"
						(effects
							(font
								(size 1.27 1.27)
							)
						)
					)
					(number "B7"
						(effects
							(font
								(size 1.27 1.27)
							)
						)
					)
				)
				(pin bidirectional line
					(at 0 -25.4 180)
					(length 3.81)
					(name "SBU_{1}"
						(effects
							(font
								(size 1.27 1.27)
							)
						)
					)
					(number "A8"
						(effects
							(font
								(size 1.27 1.27)
							)
						)
					)
				)
				(pin bidirectional line
					(at 0 -27.94 180)
					(length 3.81)
					(name "SBU_{2}"
						(effects
							(font
								(size 1.27 1.27)
							)
						)
					)
					(number "B8"
						(effects
							(font
								(size 1.27 1.27)
							)
						)
					)
				)
				(pin power_in line
					(at 0 -33.02 180)
					(length 3.81)
					(name "GND"
						(effects
							(font
								(size 1.27 1.27)
							)
						)
					)
					(number "A1"
						(effects
							(font
								(size 1.27 1.27)
							)
						)
					)
				)
				(pin passive line
					(at 0 -33.02 180)
					(length 3.81)
					(hide yes)
					(name "GND"
						(effects
							(font
								(size 1.27 1.27)
							)
						)
					)
					(number "A12"
						(effects
							(font
								(size 1.27 1.27)
							)
						)
					)
				)
				(pin passive line
					(at 0 -33.02 180)
					(length 3.81)
					(hide yes)
					(name "GND"
						(effects
							(font
								(size 1.27 1.27)
							)
						)
					)
					(number "B1"
						(effects
							(font
								(size 1.27 1.27)
							)
						)
					)
				)
				(pin passive line
					(at 0 -33.02 180)
					(length 3.81)
					(hide yes)
					(name "GND"
						(effects
							(font
								(size 1.27 1.27)
							)
						)
					)
					(number "B12"
						(effects
							(font
								(size 1.27 1.27)
							)
						)
					)
				)
				(pin passive line
					(at 0 -35.56 180)
					(length 3.81)
					(name "SH"
						(effects
							(font
								(size 1.27 1.27)
							)
						)
					)
					(number "SH"
						(effects
							(font
								(size 1.27 1.27)
							)
						)
					)
				)
			)
		)
	(symbol "antmicroWire2BoardConnectors:Molex_KK_1x4_0470531000"
			(exclude_from_sim no)
			(in_bom yes)
			(on_board yes)
			(property "Reference" "J"
				(at 20.32 -5.08 0)
				(effects
					(font
						(size 1.27 1.27)
						(thickness 0.15)
					)
					(justify left bottom)
				)
			)
			(property "Value" "Molex_KK_1x4_0470531000"
				(at 20.32 -10.16 0)
				(effects
					(font
						(size 1.27 1.27)
						(thickness 0.15)
					)
					(justify left bottom)
					(hide yes)
				)
			)
			(property "Footprint" "antmicro-footprints:Conn_Molex_KK_1x4_0470531000"
				(at 20.32 -12.7 0)
				(effects
					(font
						(size 1.27 1.27)
						(thickness 0.15)
					)
					(justify left bottom)
					(hide yes)
				)
			)
			(property "Datasheet" "https://tools.molex.com/pdm_docs/sd/470531000_sd.pdf"
				(at 20.32 -15.24 0)
				(effects
					(font
						(size 1.27 1.27)
						(thickness 0.15)
					)
					(justify left bottom)
					(hide yes)
				)
			)
			(property "Description" "Connector Header, THT,  4x1"
				(at 20.32 -25.4 0)
				(effects
					(font
						(size 1.27 1.27)
					)
					(justify left bottom)
					(hide yes)
				)
			)
			(property "MPN" "0470531000"
				(at 20.32 -7.62 0)
				(effects
					(font
						(size 1.27 1.27)
						(thickness 0.15)
					)
					(justify left bottom)
				)
			)
			(property "Manufacturer" "Molex"
				(at 20.32 -17.78 0)
				(effects
					(font
						(size 1.27 1.27)
						(thickness 0.15)
					)
					(justify left bottom)
					(hide yes)
				)
			)
			(property "Author" "Antmicro"
				(at 20.32 -20.32 0)
				(effects
					(font
						(size 1.27 1.27)
						(thickness 0.15)
					)
					(justify left bottom)
					(hide yes)
				)
			)
			(property "License" "Apache-2.0"
				(at 20.32 -22.86 0)
				(effects
					(font
						(size 1.27 1.27)
						(thickness 0.15)
					)
					(justify left bottom)
					(hide yes)
				)
			)
			(property "ki_keywords" "CONNECTOR, HEADER, WIRE-BOARD, THT"
				(at 0 0 0)
				(effects
					(font
						(size 1.27 1.27)
					)
					(hide yes)
				)
			)
			(symbol "Molex_KK_1x4_0470531000_1_1"
				(rectangle
					(start 2.54 0.127)
					(end 3.81 -0.127)
					(stroke
						(width 0.254)
						(type default)
					)
					(fill
						(type background)
					)
				)
				(rectangle
					(start 2.54 -2.413)
					(end 3.81 -2.667)
					(stroke
						(width 0.254)
						(type default)
					)
					(fill
						(type background)
					)
				)
				(rectangle
					(start 2.54 -4.953)
					(end 3.81 -5.207)
					(stroke
						(width 0.254)
						(type default)
					)
					(fill
						(type background)
					)
				)
				(rectangle
					(start 2.54 -7.493)
					(end 3.81 -7.747)
					(stroke
						(width 0.254)
						(type default)
					)
					(fill
						(type background)
					)
				)
				(rectangle
					(start 5.08 -8.89)
					(end 2.54 1.27)
					(stroke
						(width 0.254)
						(type default)
					)
					(fill
						(type background)
					)
				)
				(pin passive line
					(at 0 0 0)
					(length 2.54)
					(name "~"
						(effects
							(font
								(size 1.27 1.27)
							)
						)
					)
					(number "1"
						(effects
							(font
								(size 1.27 1.27)
							)
						)
					)
				)
				(pin passive line
					(at 0 -2.54 0)
					(length 2.54)
					(name "~"
						(effects
							(font
								(size 1.27 1.27)
							)
						)
					)
					(number "2"
						(effects
							(font
								(size 1.27 1.27)
							)
						)
					)
				)
				(pin passive line
					(at 0 -5.08 0)
					(length 2.54)
					(name "~"
						(effects
							(font
								(size 1.27 1.27)
							)
						)
					)
					(number "3"
						(effects
							(font
								(size 1.27 1.27)
							)
						)
					)
				)
				(pin passive line
					(at 0 -7.62 0)
					(length 2.54)
					(name "~"
						(effects
							(font
								(size 1.27 1.27)
							)
						)
					)
					(number "4"
						(effects
							(font
								(size 1.27 1.27)
							)
						)
					)
				)
			)
		)
	(symbol "antmicroWire2BoardConnectors:Molex_Nano-Fit_1x2_SMD_1054301202"
			(exclude_from_sim no)
			(in_bom yes)
			(on_board yes)
			(property "Reference" "J"
				(at 26.67 -2.54 0)
				(effects
					(font
						(size 1.27 1.27)
						(thickness 0.15)
					)
					(justify left bottom)
				)
			)
			(property "Value" "Molex_Nano-Fit_1x2_SMD_1054301202"
				(at 26.67 -7.62 0)
				(effects
					(font
						(size 1.27 1.27)
						(thickness 0.15)
					)
					(justify left bottom)
					(hide yes)
				)
			)
			(property "Footprint" "antmicro-footprints:Conn_Molex_Nano-Fit_1x2_SMD_1054301202"
				(at 26.67 -10.16 0)
				(effects
					(font
						(size 1.27 1.27)
						(thickness 0.15)
					)
					(justify left bottom)
					(hide yes)
				)
			)
			(property "Datasheet" "https://www.farnell.com/cad/3578051.pdf"
				(at 26.67 -12.7 0)
				(effects
					(font
						(size 1.27 1.27)
						(thickness 0.15)
					)
					(justify left bottom)
					(hide yes)
				)
			)
			(property "Description" "Pin Header, Pitch 2.5 mm, 1 Row, 2 Contacts, Nano-Fit"
				(at 26.67 -22.86 0)
				(effects
					(font
						(size 1.27 1.27)
					)
					(justify left bottom)
					(hide yes)
				)
			)
			(property "Manufacturer" "Molex"
				(at 26.67 -15.24 0)
				(effects
					(font
						(size 1.27 1.27)
						(thickness 0.15)
					)
					(justify left bottom)
					(hide yes)
				)
			)
			(property "MPN" "105430-1202"
				(at 26.67 -5.08 0)
				(effects
					(font
						(size 1.27 1.27)
						(thickness 0.15)
					)
					(justify left bottom)
				)
			)
			(property "Author" "Antmicro"
				(at 26.67 -17.78 0)
				(effects
					(font
						(size 1.27 1.27)
						(thickness 0.15)
					)
					(justify left bottom)
					(hide yes)
				)
			)
			(property "License" "Apache-2.0"
				(at 26.67 -20.32 0)
				(effects
					(font
						(size 1.27 1.27)
						(thickness 0.15)
					)
					(justify left bottom)
					(hide yes)
				)
			)
			(property "ki_keywords" "CONNECTOR, HEADER, HORIZONTAL, SMT"
				(at 0 0 0)
				(effects
					(font
						(size 1.27 1.27)
					)
					(hide yes)
				)
			)
			(symbol "Molex_Nano-Fit_1x2_SMD_1054301202_1_1"
				(rectangle
					(start 2.54 2.54)
					(end 6.35 -7.62)
					(stroke
						(width 0.254)
						(type default)
					)
					(fill
						(type background)
					)
				)
				(rectangle
					(start 2.54 -0.254)
					(end 4.1402 0.381)
					(stroke
						(width 0.254)
						(type default)
					)
					(fill
						(type background)
					)
				)
				(rectangle
					(start 2.54 -2.794)
					(end 4.1402 -2.159)
					(stroke
						(width 0.254)
						(type default)
					)
					(fill
						(type background)
					)
				)
				(rectangle
					(start 2.54 -5.334)
					(end 4.1402 -4.699)
					(stroke
						(width 0.254)
						(type default)
					)
					(fill
						(type background)
					)
				)
				(pin passive line
					(at 0 0 0)
					(length 2.54)
					(name "~"
						(effects
							(font
								(size 1.27 1.27)
							)
						)
					)
					(number "1"
						(effects
							(font
								(size 1.27 1.27)
							)
						)
					)
				)
				(pin passive line
					(at 0 -2.54 0)
					(length 2.54)
					(name "~"
						(effects
							(font
								(size 1.27 1.27)
							)
						)
					)
					(number "2"
						(effects
							(font
								(size 1.27 1.27)
							)
						)
					)
				)
				(pin passive line
					(at 0 -5.08 0)
					(length 2.54)
					(name "~"
						(effects
							(font
								(size 1.27 1.27)
							)
						)
					)
					(number "MP"
						(effects
							(font
								(size 1.27 1.27)
							)
						)
					)
				)
			)
		)
	(symbol "antmicropower:+1V0"
			(power)
			(pin_names
				(offset 0)
			)
			(exclude_from_sim no)
			(in_bom yes)
			(on_board yes)
			(property "Reference" "#PWR"
				(at 0 -3.81 0)
				(effects
					(font
						(size 1.27 1.27)
					)
					(hide yes)
				)
			)
			(property "Value" "+1V0"
				(at 0 3.556 0)
				(effects
					(font
						(size 1.27 1.27)
					)
				)
			)
			(property "Footprint" ""
				(at 0 0 0)
				(effects
					(font
						(size 1.27 1.27)
					)
					(hide yes)
				)
			)
			(property "Datasheet" ""
				(at 0 0 0)
				(effects
					(font
						(size 1.27 1.27)
					)
					(hide yes)
				)
			)
			(property "Description" ""
				(at 0 -6.35 0)
				(effects
					(font
						(size 1.27 1.27)
					)
					(justify left bottom)
					(hide yes)
				)
			)
			(symbol "+1V0_0_1"
				(polyline
					(pts
						(xy -0.762 1.27) (xy 0 2.54)
					)
					(stroke
						(width 0)
						(type default)
					)
					(fill
						(type none)
					)
				)
				(polyline
					(pts
						(xy 0 2.54) (xy 0.762 1.27)
					)
					(stroke
						(width 0)
						(type default)
					)
					(fill
						(type none)
					)
				)
				(polyline
					(pts
						(xy 0 0) (xy 0 2.54)
					)
					(stroke
						(width 0)
						(type default)
					)
					(fill
						(type none)
					)
				)
			)
			(symbol "+1V0_1_1"
				(pin power_in line
					(at 0 0 90)
					(length 0)
					(hide yes)
					(name "+1V0"
						(effects
							(font
								(size 1.27 1.27)
							)
						)
					)
					(number "1"
						(effects
							(font
								(size 1.27 1.27)
							)
						)
					)
				)
			)
		)
	(symbol "antmicropower:+1V8"
			(power)
			(pin_numbers
				(hide yes)
			)
			(pin_names
				(hide yes)
			)
			(exclude_from_sim no)
			(in_bom yes)
			(on_board yes)
			(property "Reference" "#PWR"
				(at 15.24 -2.54 0)
				(effects
					(font
						(size 1.27 1.27)
						(thickness 0.15)
					)
					(justify left bottom)
					(hide yes)
				)
			)
			(property "Value" "+1V8"
				(at -3.175 2.54 0)
				(effects
					(font
						(size 1.27 1.27)
						(thickness 0.15)
					)
					(justify left bottom)
				)
			)
			(property "Footprint" ""
				(at 15.24 -7.62 0)
				(effects
					(font
						(size 1.27 1.27)
						(thickness 0.15)
					)
					(justify left bottom)
					(hide yes)
				)
			)
			(property "Datasheet" ""
				(at 15.24 -10.16 0)
				(effects
					(font
						(size 1.27 1.27)
						(thickness 0.15)
					)
					(justify left bottom)
					(hide yes)
				)
			)
			(property "Description" ""
				(at 15.24 -12.7 0)
				(effects
					(font
						(size 1.27 1.27)
					)
					(justify left bottom)
					(hide yes)
				)
			)
			(property "Author" "Antmicro"
				(at 15.24 -5.08 0)
				(effects
					(font
						(size 1.27 1.27)
						(thickness 0.15)
					)
					(justify left bottom)
					(hide yes)
				)
			)
			(property "License" "Apache-2.0"
				(at 15.24 -7.62 0)
				(effects
					(font
						(size 1.27 1.27)
						(thickness 0.15)
					)
					(justify left bottom)
					(hide yes)
				)
			)
			(symbol "+1V8_1_1"
				(polyline
					(pts
						(xy -0.762 1.27) (xy 0 2.54)
					)
					(stroke
						(width 0)
						(type default)
					)
					(fill
						(type background)
					)
				)
				(polyline
					(pts
						(xy 0 2.54) (xy 0.762 1.27)
					)
					(stroke
						(width 0)
						(type default)
					)
					(fill
						(type background)
					)
				)
				(polyline
					(pts
						(xy 0 0) (xy 0 2.54)
					)
					(stroke
						(width 0)
						(type default)
					)
					(fill
						(type background)
					)
				)
				(pin power_in line
					(at 0 0 90)
					(length 0)
					(hide yes)
					(name "+1V8"
						(effects
							(font
								(size 1.27 1.27)
							)
						)
					)
					(number "1"
						(effects
							(font
								(size 1.27 1.27)
							)
						)
					)
				)
			)
		)
	(symbol "antmicropower:+3V3"
			(power)
			(pin_numbers
				(hide yes)
			)
			(pin_names
				(hide yes)
			)
			(exclude_from_sim no)
			(in_bom yes)
			(on_board yes)
			(property "Reference" "#PWR"
				(at 15.24 0 0)
				(effects
					(font
						(size 1.27 1.27)
						(thickness 0.15)
					)
					(justify left bottom)
					(hide yes)
				)
			)
			(property "Value" "+3V3"
				(at -3.175 2.54 0)
				(effects
					(font
						(size 1.27 1.27)
						(thickness 0.15)
					)
					(justify left bottom)
				)
			)
			(property "Footprint" ""
				(at 15.24 -7.62 0)
				(effects
					(font
						(size 1.27 1.27)
						(thickness 0.15)
					)
					(justify left bottom)
					(hide yes)
				)
			)
			(property "Datasheet" ""
				(at 15.24 -10.16 0)
				(effects
					(font
						(size 1.27 1.27)
						(thickness 0.15)
					)
					(justify left bottom)
					(hide yes)
				)
			)
			(property "Description" ""
				(at 15.24 -12.7 0)
				(effects
					(font
						(size 1.27 1.27)
					)
					(justify left bottom)
					(hide yes)
				)
			)
			(property "Author" "Antmicro"
				(at 15.24 -2.54 0)
				(effects
					(font
						(size 1.27 1.27)
						(thickness 0.15)
					)
					(justify left bottom)
					(hide yes)
				)
			)
			(property "License" "Apache-2.0"
				(at 15.24 -5.08 0)
				(effects
					(font
						(size 1.27 1.27)
						(thickness 0.15)
					)
					(justify left bottom)
					(hide yes)
				)
			)
			(symbol "+3V3_0_1"
				(polyline
					(pts
						(xy 0 2.54) (xy -0.762 1.27)
					)
					(stroke
						(width 0)
						(type default)
					)
					(fill
						(type none)
					)
				)
				(polyline
					(pts
						(xy 0 2.54) (xy 0.762 1.27)
					)
					(stroke
						(width 0)
						(type default)
					)
					(fill
						(type none)
					)
				)
				(polyline
					(pts
						(xy 0 0) (xy 0 2.54)
					)
					(stroke
						(width 0)
						(type default)
					)
					(fill
						(type none)
					)
				)
			)
			(symbol "+3V3_1_1"
				(pin power_in line
					(at 0 0 90)
					(length 0)
					(hide yes)
					(name "+3V3"
						(effects
							(font
								(size 1.27 1.27)
							)
						)
					)
					(number "1"
						(effects
							(font
								(size 1.27 1.27)
							)
						)
					)
				)
			)
		)
	(symbol "antmicropower:+3V3_AON"
			(power)
			(pin_names
				(offset 0)
			)
			(exclude_from_sim no)
			(in_bom yes)
			(on_board yes)
			(property "Reference" "#PWR"
				(at 0 -3.81 0)
				(effects
					(font
						(size 1.27 1.27)
					)
					(hide yes)
				)
			)
			(property "Value" "+3V3_AON"
				(at 0 3.556 0)
				(effects
					(font
						(size 1.27 1.27)
					)
				)
			)
			(property "Footprint" ""
				(at 0 0 0)
				(effects
					(font
						(size 1.27 1.27)
					)
					(hide yes)
				)
			)
			(property "Datasheet" ""
				(at 0 0 0)
				(effects
					(font
						(size 1.27 1.27)
					)
					(hide yes)
				)
			)
			(property "Description" ""
				(at 0 -6.35 0)
				(effects
					(font
						(size 1.27 1.27)
					)
					(justify left bottom)
					(hide yes)
				)
			)
			(symbol "+3V3_AON_0_1"
				(polyline
					(pts
						(xy -0.762 1.27) (xy 0 2.54)
					)
					(stroke
						(width 0)
						(type default)
					)
					(fill
						(type none)
					)
				)
				(polyline
					(pts
						(xy 0 2.54) (xy 0.762 1.27)
					)
					(stroke
						(width 0)
						(type default)
					)
					(fill
						(type none)
					)
				)
				(polyline
					(pts
						(xy 0 0) (xy 0 2.54)
					)
					(stroke
						(width 0)
						(type default)
					)
					(fill
						(type none)
					)
				)
			)
			(symbol "+3V3_AON_1_1"
				(pin power_in line
					(at 0 0 90)
					(length 0)
					(hide yes)
					(name "+3V3_AON"
						(effects
							(font
								(size 1.27 1.27)
							)
						)
					)
					(number "1"
						(effects
							(font
								(size 1.27 1.27)
							)
						)
					)
				)
			)
		)
	(symbol "antmicropower:GND"
			(power)
			(pin_numbers
				(hide yes)
			)
			(pin_names
				(hide yes)
			)
			(exclude_from_sim no)
			(in_bom yes)
			(on_board yes)
			(property "Reference" "#PWR"
				(at 8.89 -2.54 0)
				(effects
					(font
						(size 1.27 1.27)
						(thickness 0.15)
					)
					(justify left bottom)
					(hide yes)
				)
			)
			(property "Value" "GND"
				(at 8.89 -5.08 0)
				(effects
					(font
						(size 1.27 1.27)
						(thickness 0.15)
					)
					(justify left bottom)
				)
			)
			(property "Footprint" ""
				(at 8.89 -7.62 0)
				(effects
					(font
						(size 1.27 1.27)
						(thickness 0.15)
					)
					(justify left bottom)
					(hide yes)
				)
			)
			(property "Datasheet" ""
				(at 8.89 -12.7 0)
				(effects
					(font
						(size 1.27 1.27)
						(thickness 0.15)
					)
					(justify left bottom)
					(hide yes)
				)
			)
			(property "Description" ""
				(at 8.89 -15.24 0)
				(effects
					(font
						(size 1.27 1.27)
					)
					(justify left bottom)
					(hide yes)
				)
			)
			(property "Author" "Antmicro"
				(at 8.89 -7.62 0)
				(effects
					(font
						(size 1.27 1.27)
						(thickness 0.15)
					)
					(justify left bottom)
					(hide yes)
				)
			)
			(property "License" "Apache-2.0"
				(at 8.89 -10.16 0)
				(effects
					(font
						(size 1.27 1.27)
						(thickness 0.15)
					)
					(justify left bottom)
					(hide yes)
				)
			)
			(symbol "GND_1_1"
				(polyline
					(pts
						(xy 0 0) (xy 0 -1.27) (xy 1.27 -1.27) (xy 0 -2.54) (xy -1.27 -1.27) (xy 0 -1.27)
					)
					(stroke
						(width 0)
						(type default)
					)
					(fill
						(type none)
					)
				)
				(pin power_in line
					(at 0 0 270)
					(length 0)
					(name "GND"
						(effects
							(font
								(size 1.27 1.27)
							)
						)
					)
					(number "1"
						(effects
							(font
								(size 1.27 1.27)
							)
						)
					)
				)
			)
		)
	(symbol "antmicropower:PWR_FLAG"
			(power)
			(pin_numbers
				(hide yes)
			)
			(pin_names
				(offset 0)
				(hide yes)
			)
			(exclude_from_sim no)
			(in_bom yes)
			(on_board yes)
			(property "Reference" "#FLG"
				(at 0 1.905 0)
				(effects
					(font
						(size 1.27 1.27)
					)
					(hide yes)
				)
			)
			(property "Value" "PWR_FLAG"
				(at 0 3.81 0)
				(effects
					(font
						(size 1.27 1.27)
					)
				)
			)
			(property "Footprint" ""
				(at 0 0 0)
				(effects
					(font
						(size 1.27 1.27)
					)
					(hide yes)
				)
			)
			(property "Datasheet" ""
				(at 0 0 0)
				(effects
					(font
						(size 1.27 1.27)
					)
					(hide yes)
				)
			)
			(property "Description" ""
				(at 0 -2.54 0)
				(effects
					(font
						(size 1.27 1.27)
					)
					(justify left bottom)
					(hide yes)
				)
			)
			(symbol "PWR_FLAG_0_0"
				(pin power_out line
					(at 0 0 90)
					(length 0)
					(name "pwr"
						(effects
							(font
								(size 1.27 1.27)
							)
						)
					)
					(number "1"
						(effects
							(font
								(size 1.27 1.27)
							)
						)
					)
				)
			)
			(symbol "PWR_FLAG_0_1"
				(polyline
					(pts
						(xy 0 0) (xy 0 1.27) (xy -1.016 1.905) (xy 0 2.54) (xy 1.016 1.905) (xy 0 1.27)
					)
					(stroke
						(width 0)
						(type default)
					)
					(fill
						(type none)
					)
				)
			)
		)
	(symbol "antmicropower:VCC"
			(power)
			(pin_names
				(offset 0)
			)
			(exclude_from_sim no)
			(in_bom yes)
			(on_board yes)
			(property "Reference" "#PWR"
				(at 0 -3.81 0)
				(effects
					(font
						(size 1.27 1.27)
					)
					(hide yes)
				)
			)
			(property "Value" "VCC"
				(at 0 3.81 0)
				(effects
					(font
						(size 1.27 1.27)
					)
				)
			)
			(property "Footprint" ""
				(at 0 0 0)
				(effects
					(font
						(size 1.27 1.27)
					)
					(hide yes)
				)
			)
			(property "Datasheet" ""
				(at 0 0 0)
				(effects
					(font
						(size 1.27 1.27)
					)
					(hide yes)
				)
			)
			(property "Description" ""
				(at 0 -6.35 0)
				(effects
					(font
						(size 1.27 1.27)
					)
					(justify left bottom)
					(hide yes)
				)
			)
			(symbol "VCC_0_1"
				(polyline
					(pts
						(xy -0.762 1.27) (xy 0 2.54)
					)
					(stroke
						(width 0)
						(type default)
					)
					(fill
						(type none)
					)
				)
				(polyline
					(pts
						(xy 0 2.54) (xy 0.762 1.27)
					)
					(stroke
						(width 0)
						(type default)
					)
					(fill
						(type none)
					)
				)
				(polyline
					(pts
						(xy 0 0) (xy 0 2.54)
					)
					(stroke
						(width 0)
						(type default)
					)
					(fill
						(type none)
					)
				)
			)
			(symbol "VCC_1_1"
				(pin power_in line
					(at 0 0 90)
					(length 0)
					(hide yes)
					(name "VCC"
						(effects
							(font
								(size 1.27 1.27)
							)
						)
					)
					(number "1"
						(effects
							(font
								(size 1.27 1.27)
							)
						)
					)
				)
			)
		)
	(symbol "antmicropower:VDD"
			(power)
			(pin_names
				(offset 0)
			)
			(exclude_from_sim no)
			(in_bom yes)
			(on_board yes)
			(property "Reference" "#PWR"
				(at 0 -3.81 0)
				(effects
					(font
						(size 1.27 1.27)
					)
					(hide yes)
				)
			)
			(property "Value" "VDD"
				(at 0 3.81 0)
				(effects
					(font
						(size 1.27 1.27)
					)
				)
			)
			(property "Footprint" ""
				(at 0 0 0)
				(effects
					(font
						(size 1.27 1.27)
					)
					(hide yes)
				)
			)
			(property "Datasheet" ""
				(at 0 0 0)
				(effects
					(font
						(size 1.27 1.27)
					)
					(hide yes)
				)
			)
			(property "Description" ""
				(at 0 -6.35 0)
				(effects
					(font
						(size 1.27 1.27)
					)
					(justify left bottom)
					(hide yes)
				)
			)
			(symbol "VDD_0_1"
				(polyline
					(pts
						(xy -0.762 1.27) (xy 0 2.54)
					)
					(stroke
						(width 0)
						(type default)
					)
					(fill
						(type none)
					)
				)
				(polyline
					(pts
						(xy 0 2.54) (xy 0.762 1.27)
					)
					(stroke
						(width 0)
						(type default)
					)
					(fill
						(type none)
					)
				)
				(polyline
					(pts
						(xy 0 0) (xy 0 2.54)
					)
					(stroke
						(width 0)
						(type default)
					)
					(fill
						(type none)
					)
				)
			)
			(symbol "VDD_1_1"
				(pin power_in line
					(at 0 0 90)
					(length 0)
					(hide yes)
					(name "VDD"
						(effects
							(font
								(size 1.27 1.27)
							)
						)
					)
					(number "1"
						(effects
							(font
								(size 1.27 1.27)
							)
						)
					)
				)
			)
		)
)
